(kicad_sch
	(version 20250114)
	(generator "eeschema")
	(generator_version "9.0")
	(paper "A3")
	(title_block
		(title "CM4 Baseboard")
		(date "2026-01-05")
		(rev "1.1.1")
		(company "Antmicro Ltd")
		(comment 1 "www.antmicro.com")
	)
	(bus_alias "CamCtrl"
		(members "EN" "VSYNC0" "VSYNC1")
	)
	(text "Power switches"
		(exclude_from_sim no)
		(at 82.55 102.235 0)
		(effects
			(font
				(size 4 4)
				(thickness 0.8)
				(bold yes)
			)
			(justify left bottom)
		)
	)
	(text "CSI connector"
		(exclude_from_sim no)
		(at 278.13 49.53 0)
		(effects
			(font
				(size 4 4)
				(thickness 0.8)
				(bold yes)
			)
			(justify left bottom)
		)
	)
	(text "MIPI CSI-2 input via \nAntmico Dual CSI connector"
		(exclude_from_sim no)
		(at 279.4 54.61 0)
		(effects
			(font
				(size 1.27 1.27)
			)
			(justify left bottom)
		)
	)
	(text "Both switches set to 1.5A current limit\n"
		(exclude_from_sim no)
		(at 83.82 105.41 0)
		(effects
			(font
				(size 1.27 1.27)
			)
			(justify left bottom)
		)
	)
	(junction
		(at 152.4 173.99)
		(diameter 0)
		(color 0 0 0 0)
	)
	(junction
		(at 307.34 184.15)
		(diameter 0)
		(color 0 0 0 0)
	)
	(junction
		(at 316.23 191.77)
		(diameter 0)
		(color 0 0 0 0)
	)
	(junction
		(at 316.23 90.17)
		(diameter 0)
		(color 0 0 0 0)
	)
	(junction
		(at 316.23 135.89)
		(diameter 0)
		(color 0 0 0 0)
	)
	(junction
		(at 283.21 184.15)
		(diameter 0)
		(color 0 0 0 0)
	)
	(junction
		(at 101.6 134.62)
		(diameter 0)
		(color 0 0 0 0)
	)
	(junction
		(at 316.23 97.79)
		(diameter 0)
		(color 0 0 0 0)
	)
	(junction
		(at 118.11 132.08)
		(diameter 0)
		(color 0 0 0 0)
	)
	(junction
		(at 118.11 176.53)
		(diameter 0)
		(color 0 0 0 0)
	)
	(junction
		(at 278.13 179.07)
		(diameter 0)
		(color 0 0 0 0)
	)
	(junction
		(at 93.98 134.62)
		(diameter 0)
		(color 0 0 0 0)
	)
	(junction
		(at 299.72 179.07)
		(diameter 0)
		(color 0 0 0 0)
	)
	(junction
		(at 109.22 163.83)
		(diameter 0)
		(color 0 0 0 0)
	)
	(junction
		(at 316.23 189.23)
		(diameter 0)
		(color 0 0 0 0)
	)
	(junction
		(at 313.69 179.07)
		(diameter 0)
		(color 0 0 0 0)
	)
	(junction
		(at 316.23 128.27)
		(diameter 0)
		(color 0 0 0 0)
	)
	(junction
		(at 152.4 129.54)
		(diameter 0)
		(color 0 0 0 0)
	)
	(junction
		(at 313.69 184.15)
		(diameter 0)
		(color 0 0 0 0)
	)
	(junction
		(at 118.11 163.83)
		(diameter 0)
		(color 0 0 0 0)
	)
	(junction
		(at 118.11 119.38)
		(diameter 0)
		(color 0 0 0 0)
	)
	(junction
		(at 316.23 105.41)
		(diameter 0)
		(color 0 0 0 0)
	)
	(junction
		(at 109.22 119.38)
		(diameter 0)
		(color 0 0 0 0)
	)
	(no_connect
		(at 318.77 171.45)
	)
	(no_connect
		(at 318.77 176.53)
	)
	(no_connect
		(at 318.77 64.77)
	)
	(no_connect
		(at 318.77 62.23)
	)
	(no_connect
		(at 318.77 168.91)
	)
	(no_connect
		(at 318.77 173.99)
	)
	(no_connect
		(at 318.77 153.67)
	)
	(no_connect
		(at 318.77 148.59)
	)
	(no_connect
		(at 318.77 102.87)
	)
	(no_connect
		(at 318.77 95.25)
	)
	(no_connect
		(at 318.77 151.13)
	)
	(no_connect
		(at 318.77 69.85)
	)
	(no_connect
		(at 318.77 100.33)
	)
	(no_connect
		(at 318.77 138.43)
	)
	(no_connect
		(at 318.77 92.71)
	)
	(no_connect
		(at 318.77 67.31)
	)
	(no_connect
		(at 318.77 156.21)
	)
	(no_connect
		(at 318.77 143.51)
	)
	(bus_entry
		(at 295.91 115.57)
		(size 2.54 2.54)
		(stroke
			(width 0)
			(type default)
		)
	)
	(bus_entry
		(at 78.74 132.08)
		(size 2.54 2.54)
		(stroke
			(width 0)
			(type default)
		)
	)
	(bus_entry
		(at 295.91 156.21)
		(size 2.54 2.54)
		(stroke
			(width 0)
			(type default)
		)
	)
	(bus_entry
		(at 295.91 82.55)
		(size 2.54 2.54)
		(stroke
			(width 0)
			(type default)
		)
	)
	(bus_entry
		(at 295.91 69.85)
		(size 2.54 2.54)
		(stroke
			(width 0)
			(type default)
		)
	)
	(bus_entry
		(at 295.91 105.41)
		(size 2.54 2.54)
		(stroke
			(width 0)
			(type default)
		)
	)
	(bus_entry
		(at 295.91 113.03)
		(size 2.54 2.54)
		(stroke
			(width 0)
			(type default)
		)
	)
	(bus_entry
		(at 295.91 123.19)
		(size 2.54 2.54)
		(stroke
			(width 0)
			(type default)
		)
	)
	(bus_entry
		(at 295.91 130.81)
		(size 2.54 2.54)
		(stroke
			(width 0)
			(type default)
		)
	)
	(bus_entry
		(at 295.91 161.29)
		(size 2.54 2.54)
		(stroke
			(width 0)
			(type default)
		)
	)
	(bus_entry
		(at 295.91 161.29)
		(size 2.54 2.54)
		(stroke
			(width 0)
			(type default)
		)
	)
	(bus_entry
		(at 295.91 120.65)
		(size 2.54 2.54)
		(stroke
			(width 0)
			(type default)
		)
	)
	(bus_entry
		(at 295.91 107.95)
		(size 2.54 2.54)
		(stroke
			(width 0)
			(type default)
		)
	)
	(bus_entry
		(at 295.91 163.83)
		(size 2.54 2.54)
		(stroke
			(width 0)
			(type default)
		)
	)
	(bus_entry
		(at 295.91 138.43)
		(size 2.54 2.54)
		(stroke
			(width 0)
			(type default)
		)
	)
	(bus_entry
		(at 295.91 110.49)
		(size 2.54 2.54)
		(stroke
			(width 0)
			(type default)
		)
	)
	(bus_entry
		(at 295.91 72.39)
		(size 2.54 2.54)
		(stroke
			(width 0)
			(type default)
		)
	)
	(bus_entry
		(at 295.91 161.29)
		(size 2.54 2.54)
		(stroke
			(width 0)
			(type default)
		)
	)
	(bus_entry
		(at 295.91 85.09)
		(size 2.54 2.54)
		(stroke
			(width 0)
			(type default)
		)
	)
	(bus_entry
		(at 295.91 118.11)
		(size 2.54 2.54)
		(stroke
			(width 0)
			(type default)
		)
	)
	(bus_entry
		(at 295.91 74.93)
		(size 2.54 2.54)
		(stroke
			(width 0)
			(type default)
		)
	)
	(bus_entry
		(at 295.91 143.51)
		(size 2.54 2.54)
		(stroke
			(width 0)
			(type default)
		)
	)
	(bus_entry
		(at 295.91 128.27)
		(size 2.54 2.54)
		(stroke
			(width 0)
			(type default)
		)
	)
	(bus_entry
		(at 295.91 77.47)
		(size 2.54 2.54)
		(stroke
			(width 0)
			(type default)
		)
	)
	(bus_entry
		(at 295.91 158.75)
		(size 2.54 2.54)
		(stroke
			(width 0)
			(type default)
		)
	)
	(bus
		(pts
			(xy 295.91 74.93) (xy 295.91 77.47)
		)
		(stroke
			(width 0)
			(type default)
		)
	)
	(wire
		(pts
			(xy 138.43 179.07) (xy 138.43 184.15)
		)
		(stroke
			(width 0)
			(type default)
		)
	)
	(wire
		(pts
			(xy 109.22 163.83) (xy 118.11 163.83)
		)
		(stroke
			(width 0)
			(type default)
		)
	)
	(bus
		(pts
			(xy 295.91 128.27) (xy 295.91 130.81)
		)
		(stroke
			(width 0)
			(type default)
		)
	)
	(wire
		(pts
			(xy 278.13 179.07) (xy 278.13 186.69)
		)
		(stroke
			(width 0)
			(type default)
		)
	)
	(bus
		(pts
			(xy 295.91 69.85) (xy 295.91 72.39)
		)
		(stroke
			(width 0)
			(type default)
		)
	)
	(wire
		(pts
			(xy 298.45 163.83) (xy 318.77 163.83)
		)
		(stroke
			(width 0)
			(type default)
		)
	)
	(wire
		(pts
			(xy 118.11 163.83) (xy 118.11 165.1)
		)
		(stroke
			(width 0)
			(type default)
		)
	)
	(wire
		(pts
			(xy 152.4 129.54) (xy 161.29 129.54)
		)
		(stroke
			(width 0)
			(type default)
		)
	)
	(wire
		(pts
			(xy 298.45 125.73) (xy 318.77 125.73)
		)
		(stroke
			(width 0)
			(type default)
		)
	)
	(wire
		(pts
			(xy 298.45 87.63) (xy 318.77 87.63)
		)
		(stroke
			(width 0)
			(type default)
		)
	)
	(bus
		(pts
			(xy 295.91 156.21) (xy 295.91 158.75)
		)
		(stroke
			(width 0)
			(type default)
		)
	)
	(wire
		(pts
			(xy 307.34 184.15) (xy 313.69 184.15)
		)
		(stroke
			(width 0)
			(type default)
		)
	)
	(wire
		(pts
			(xy 307.34 184.15) (xy 307.34 186.69)
		)
		(stroke
			(width 0)
			(type default)
		)
	)
	(wire
		(pts
			(xy 316.23 90.17) (xy 318.77 90.17)
		)
		(stroke
			(width 0)
			(type default)
		)
	)
	(wire
		(pts
			(xy 316.23 97.79) (xy 316.23 105.41)
		)
		(stroke
			(width 0)
			(type default)
		)
	)
	(wire
		(pts
			(xy 318.77 82.55) (xy 316.23 82.55)
		)
		(stroke
			(width 0)
			(type default)
		)
	)
	(polyline
		(pts
			(xy 195.58 12.7) (xy 195.58 284.48)
		)
		(stroke
			(width 0)
			(type default)
		)
	)
	(wire
		(pts
			(xy 101.6 179.07) (xy 121.92 179.07)
		)
		(stroke
			(width 0)
			(type default)
		)
	)
	(bus
		(pts
			(xy 295.91 82.55) (xy 295.91 85.09)
		)
		(stroke
			(width 0)
			(type default)
		)
	)
	(wire
		(pts
			(xy 118.11 119.38) (xy 118.11 120.65)
		)
		(stroke
			(width 0)
			(type default)
		)
	)
	(wire
		(pts
			(xy 137.16 176.53) (xy 143.51 176.53)
		)
		(stroke
			(width 0)
			(type default)
		)
	)
	(wire
		(pts
			(xy 137.16 173.99) (xy 152.4 173.99)
		)
		(stroke
			(width 0)
			(type default)
		)
	)
	(bus
		(pts
			(xy 293.37 104.14) (xy 295.91 104.14)
		)
		(stroke
			(width 0)
			(type default)
		)
	)
	(wire
		(pts
			(xy 137.16 179.07) (xy 138.43 179.07)
		)
		(stroke
			(width 0)
			(type default)
		)
	)
	(wire
		(pts
			(xy 101.6 179.07) (xy 101.6 134.62)
		)
		(stroke
			(width 0)
			(type default)
		)
	)
	(wire
		(pts
			(xy 137.16 132.08) (xy 143.51 132.08)
		)
		(stroke
			(width 0)
			(type default)
		)
	)
	(bus
		(pts
			(xy 295.91 118.11) (xy 295.91 120.65)
		)
		(stroke
			(width 0)
			(type default)
		)
	)
	(wire
		(pts
			(xy 138.43 134.62) (xy 138.43 139.7)
		)
		(stroke
			(width 0)
			(type default)
		)
	)
	(wire
		(pts
			(xy 109.22 118.11) (xy 109.22 119.38)
		)
		(stroke
			(width 0)
			(type default)
		)
	)
	(wire
		(pts
			(xy 152.4 172.72) (xy 152.4 173.99)
		)
		(stroke
			(width 0)
			(type default)
		)
	)
	(bus
		(pts
			(xy 295.91 161.29) (xy 295.91 163.83)
		)
		(stroke
			(width 0)
			(type default)
		)
	)
	(wire
		(pts
			(xy 298.45 118.11) (xy 318.77 118.11)
		)
		(stroke
			(width 0)
			(type default)
		)
	)
	(wire
		(pts
			(xy 283.21 193.04) (xy 283.21 191.77)
		)
		(stroke
			(width 0)
			(type default)
		)
	)
	(wire
		(pts
			(xy 298.45 110.49) (xy 318.77 110.49)
		)
		(stroke
			(width 0)
			(type default)
		)
	)
	(wire
		(pts
			(xy 298.45 80.01) (xy 318.77 80.01)
		)
		(stroke
			(width 0)
			(type default)
		)
	)
	(bus
		(pts
			(xy 295.91 107.95) (xy 295.91 110.49)
		)
		(stroke
			(width 0)
			(type default)
		)
	)
	(wire
		(pts
			(xy 152.4 128.27) (xy 152.4 129.54)
		)
		(stroke
			(width 0)
			(type default)
		)
	)
	(wire
		(pts
			(xy 298.45 107.95) (xy 318.77 107.95)
		)
		(stroke
			(width 0)
			(type default)
		)
	)
	(wire
		(pts
			(xy 120.65 173.99) (xy 120.65 163.83)
		)
		(stroke
			(width 0)
			(type default)
		)
	)
	(wire
		(pts
			(xy 316.23 128.27) (xy 318.77 128.27)
		)
		(stroke
			(width 0)
			(type default)
		)
	)
	(wire
		(pts
			(xy 278.13 179.07) (xy 299.72 179.07)
		)
		(stroke
			(width 0)
			(type default)
		)
	)
	(wire
		(pts
			(xy 299.72 179.07) (xy 299.72 186.69)
		)
		(stroke
			(width 0)
			(type default)
		)
	)
	(bus
		(pts
			(xy 295.91 72.39) (xy 295.91 74.93)
		)
		(stroke
			(width 0)
			(type default)
		)
	)
	(wire
		(pts
			(xy 316.23 189.23) (xy 318.77 189.23)
		)
		(stroke
			(width 0)
			(type default)
		)
	)
	(bus
		(pts
			(xy 295.91 113.03) (xy 295.91 115.57)
		)
		(stroke
			(width 0)
			(type default)
		)
	)
	(wire
		(pts
			(xy 275.59 179.07) (xy 278.13 179.07)
		)
		(stroke
			(width 0)
			(type default)
		)
	)
	(wire
		(pts
			(xy 275.59 184.15) (xy 283.21 184.15)
		)
		(stroke
			(width 0)
			(type default)
		)
	)
	(wire
		(pts
			(xy 316.23 90.17) (xy 316.23 97.79)
		)
		(stroke
			(width 0)
			(type default)
		)
	)
	(wire
		(pts
			(xy 93.98 142.24) (xy 93.98 144.78)
		)
		(stroke
			(width 0)
			(type default)
		)
	)
	(wire
		(pts
			(xy 298.45 158.75) (xy 318.77 158.75)
		)
		(stroke
			(width 0)
			(type default)
		)
	)
	(bus
		(pts
			(xy 295.91 77.47) (xy 295.91 82.55)
		)
		(stroke
			(width 0)
			(type default)
		)
	)
	(wire
		(pts
			(xy 137.16 129.54) (xy 152.4 129.54)
		)
		(stroke
			(width 0)
			(type default)
		)
	)
	(wire
		(pts
			(xy 298.45 123.19) (xy 318.77 123.19)
		)
		(stroke
			(width 0)
			(type default)
		)
	)
	(wire
		(pts
			(xy 316.23 135.89) (xy 316.23 189.23)
		)
		(stroke
			(width 0)
			(type default)
		)
	)
	(wire
		(pts
			(xy 121.92 129.54) (xy 120.65 129.54)
		)
		(stroke
			(width 0)
			(type default)
		)
	)
	(wire
		(pts
			(xy 109.22 125.73) (xy 109.22 127)
		)
		(stroke
			(width 0)
			(type default)
		)
	)
	(bus
		(pts
			(xy 293.37 160.02) (xy 295.91 160.02)
		)
		(stroke
			(width 0)
			(type default)
		)
	)
	(wire
		(pts
			(xy 298.45 74.93) (xy 318.77 74.93)
		)
		(stroke
			(width 0)
			(type default)
		)
	)
	(wire
		(pts
			(xy 316.23 105.41) (xy 318.77 105.41)
		)
		(stroke
			(width 0)
			(type default)
		)
	)
	(wire
		(pts
			(xy 143.51 138.43) (xy 143.51 139.7)
		)
		(stroke
			(width 0)
			(type default)
		)
	)
	(wire
		(pts
			(xy 116.84 176.53) (xy 118.11 176.53)
		)
		(stroke
			(width 0)
			(type default)
		)
	)
	(bus
		(pts
			(xy 295.91 137.16) (xy 295.91 138.43)
		)
		(stroke
			(width 0)
			(type default)
		)
	)
	(wire
		(pts
			(xy 109.22 162.56) (xy 109.22 163.83)
		)
		(stroke
			(width 0)
			(type default)
		)
	)
	(wire
		(pts
			(xy 316.23 82.55) (xy 316.23 90.17)
		)
		(stroke
			(width 0)
			(type default)
		)
	)
	(wire
		(pts
			(xy 152.4 130.81) (xy 152.4 129.54)
		)
		(stroke
			(width 0)
			(type default)
		)
	)
	(wire
		(pts
			(xy 298.45 130.81) (xy 318.77 130.81)
		)
		(stroke
			(width 0)
			(type default)
		)
	)
	(bus
		(pts
			(xy 295.91 123.19) (xy 295.91 128.27)
		)
		(stroke
			(width 0)
			(type default)
		)
	)
	(wire
		(pts
			(xy 316.23 189.23) (xy 316.23 191.77)
		)
		(stroke
			(width 0)
			(type default)
		)
	)
	(wire
		(pts
			(xy 278.13 193.04) (xy 278.13 191.77)
		)
		(stroke
			(width 0)
			(type default)
		)
	)
	(wire
		(pts
			(xy 143.51 182.88) (xy 143.51 184.15)
		)
		(stroke
			(width 0)
			(type default)
		)
	)
	(wire
		(pts
			(xy 118.11 125.73) (xy 118.11 132.08)
		)
		(stroke
			(width 0)
			(type default)
		)
	)
	(bus
		(pts
			(xy 295.91 120.65) (xy 295.91 123.19)
		)
		(stroke
			(width 0)
			(type default)
		)
	)
	(bus
		(pts
			(xy 293.37 154.94) (xy 295.91 154.94)
		)
		(stroke
			(width 0)
			(type default)
		)
	)
	(wire
		(pts
			(xy 298.45 115.57) (xy 318.77 115.57)
		)
		(stroke
			(width 0)
			(type default)
		)
	)
	(wire
		(pts
			(xy 298.45 140.97) (xy 318.77 140.97)
		)
		(stroke
			(width 0)
			(type default)
		)
	)
	(wire
		(pts
			(xy 316.23 105.41) (xy 316.23 128.27)
		)
		(stroke
			(width 0)
			(type default)
		)
	)
	(wire
		(pts
			(xy 137.16 134.62) (xy 138.43 134.62)
		)
		(stroke
			(width 0)
			(type default)
		)
	)
	(wire
		(pts
			(xy 298.45 161.29) (xy 318.77 161.29)
		)
		(stroke
			(width 0)
			(type default)
		)
	)
	(wire
		(pts
			(xy 118.11 163.83) (xy 120.65 163.83)
		)
		(stroke
			(width 0)
			(type default)
		)
	)
	(wire
		(pts
			(xy 316.23 191.77) (xy 316.23 193.04)
		)
		(stroke
			(width 0)
			(type default)
		)
	)
	(wire
		(pts
			(xy 298.45 113.03) (xy 318.77 113.03)
		)
		(stroke
			(width 0)
			(type default)
		)
	)
	(wire
		(pts
			(xy 152.4 142.24) (xy 152.4 143.51)
		)
		(stroke
			(width 0)
			(type default)
		)
	)
	(wire
		(pts
			(xy 143.51 176.53) (xy 143.51 177.8)
		)
		(stroke
			(width 0)
			(type default)
		)
	)
	(wire
		(pts
			(xy 109.22 163.83) (xy 109.22 165.1)
		)
		(stroke
			(width 0)
			(type default)
		)
	)
	(bus
		(pts
			(xy 293.37 137.16) (xy 295.91 137.16)
		)
		(stroke
			(width 0)
			(type default)
		)
	)
	(wire
		(pts
			(xy 298.45 85.09) (xy 318.77 85.09)
		)
		(stroke
			(width 0)
			(type default)
		)
	)
	(wire
		(pts
			(xy 109.22 119.38) (xy 118.11 119.38)
		)
		(stroke
			(width 0)
			(type default)
		)
	)
	(bus
		(pts
			(xy 295.91 154.94) (xy 295.91 156.21)
		)
		(stroke
			(width 0)
			(type default)
		)
	)
	(wire
		(pts
			(xy 298.45 77.47) (xy 318.77 77.47)
		)
		(stroke
			(width 0)
			(type default)
		)
	)
	(wire
		(pts
			(xy 307.34 191.77) (xy 307.34 193.04)
		)
		(stroke
			(width 0)
			(type default)
		)
	)
	(wire
		(pts
			(xy 313.69 181.61) (xy 313.69 179.07)
		)
		(stroke
			(width 0)
			(type default)
		)
	)
	(wire
		(pts
			(xy 313.69 186.69) (xy 318.77 186.69)
		)
		(stroke
			(width 0)
			(type default)
		)
	)
	(wire
		(pts
			(xy 109.22 119.38) (xy 109.22 120.65)
		)
		(stroke
			(width 0)
			(type default)
		)
	)
	(wire
		(pts
			(xy 93.98 134.62) (xy 101.6 134.62)
		)
		(stroke
			(width 0)
			(type default)
		)
	)
	(wire
		(pts
			(xy 152.4 180.34) (xy 152.4 181.61)
		)
		(stroke
			(width 0)
			(type default)
		)
	)
	(wire
		(pts
			(xy 299.72 191.77) (xy 299.72 193.04)
		)
		(stroke
			(width 0)
			(type default)
		)
	)
	(wire
		(pts
			(xy 116.84 132.08) (xy 118.11 132.08)
		)
		(stroke
			(width 0)
			(type default)
		)
	)
	(wire
		(pts
			(xy 313.69 184.15) (xy 313.69 186.69)
		)
		(stroke
			(width 0)
			(type default)
		)
	)
	(wire
		(pts
			(xy 283.21 184.15) (xy 283.21 186.69)
		)
		(stroke
			(width 0)
			(type default)
		)
	)
	(wire
		(pts
			(xy 318.77 181.61) (xy 313.69 181.61)
		)
		(stroke
			(width 0)
			(type default)
		)
	)
	(wire
		(pts
			(xy 118.11 132.08) (xy 121.92 132.08)
		)
		(stroke
			(width 0)
			(type default)
		)
	)
	(wire
		(pts
			(xy 121.92 173.99) (xy 120.65 173.99)
		)
		(stroke
			(width 0)
			(type default)
		)
	)
	(wire
		(pts
			(xy 152.4 173.99) (xy 161.29 173.99)
		)
		(stroke
			(width 0)
			(type default)
		)
	)
	(wire
		(pts
			(xy 316.23 135.89) (xy 318.77 135.89)
		)
		(stroke
			(width 0)
			(type default)
		)
	)
	(wire
		(pts
			(xy 283.21 184.15) (xy 307.34 184.15)
		)
		(stroke
			(width 0)
			(type default)
		)
	)
	(wire
		(pts
			(xy 298.45 146.05) (xy 318.77 146.05)
		)
		(stroke
			(width 0)
			(type default)
		)
	)
	(wire
		(pts
			(xy 299.72 179.07) (xy 313.69 179.07)
		)
		(stroke
			(width 0)
			(type default)
		)
	)
	(bus
		(pts
			(xy 295.91 110.49) (xy 295.91 113.03)
		)
		(stroke
			(width 0)
			(type default)
		)
	)
	(bus
		(pts
			(xy 295.91 104.14) (xy 295.91 105.41)
		)
		(stroke
			(width 0)
			(type default)
		)
	)
	(bus
		(pts
			(xy 295.91 160.02) (xy 295.91 161.29)
		)
		(stroke
			(width 0)
			(type default)
		)
	)
	(wire
		(pts
			(xy 120.65 129.54) (xy 120.65 119.38)
		)
		(stroke
			(width 0)
			(type default)
		)
	)
	(wire
		(pts
			(xy 118.11 176.53) (xy 121.92 176.53)
		)
		(stroke
			(width 0)
			(type default)
		)
	)
	(wire
		(pts
			(xy 316.23 97.79) (xy 318.77 97.79)
		)
		(stroke
			(width 0)
			(type default)
		)
	)
	(wire
		(pts
			(xy 109.22 170.18) (xy 109.22 171.45)
		)
		(stroke
			(width 0)
			(type default)
		)
	)
	(bus
		(pts
			(xy 293.37 67.31) (xy 295.91 67.31)
		)
		(stroke
			(width 0)
			(type default)
		)
	)
	(bus
		(pts
			(xy 295.91 138.43) (xy 295.91 143.51)
		)
		(stroke
			(width 0)
			(type default)
		)
	)
	(wire
		(pts
			(xy 316.23 128.27) (xy 316.23 135.89)
		)
		(stroke
			(width 0)
			(type default)
		)
	)
	(wire
		(pts
			(xy 298.45 133.35) (xy 318.77 133.35)
		)
		(stroke
			(width 0)
			(type default)
		)
	)
	(bus
		(pts
			(xy 295.91 115.57) (xy 295.91 118.11)
		)
		(stroke
			(width 0)
			(type default)
		)
	)
	(bus
		(pts
			(xy 295.91 67.31) (xy 295.91 69.85)
		)
		(stroke
			(width 0)
			(type default)
		)
	)
	(wire
		(pts
			(xy 143.51 132.08) (xy 143.51 133.35)
		)
		(stroke
			(width 0)
			(type default)
		)
	)
	(wire
		(pts
			(xy 152.4 173.99) (xy 152.4 175.26)
		)
		(stroke
			(width 0)
			(type default)
		)
	)
	(wire
		(pts
			(xy 152.4 186.69) (xy 152.4 187.96)
		)
		(stroke
			(width 0)
			(type default)
		)
	)
	(wire
		(pts
			(xy 313.69 179.07) (xy 318.77 179.07)
		)
		(stroke
			(width 0)
			(type default)
		)
	)
	(wire
		(pts
			(xy 101.6 134.62) (xy 121.92 134.62)
		)
		(stroke
			(width 0)
			(type default)
		)
	)
	(wire
		(pts
			(xy 152.4 135.89) (xy 152.4 137.16)
		)
		(stroke
			(width 0)
			(type default)
		)
	)
	(wire
		(pts
			(xy 118.11 119.38) (xy 120.65 119.38)
		)
		(stroke
			(width 0)
			(type default)
		)
	)
	(wire
		(pts
			(xy 298.45 166.37) (xy 318.77 166.37)
		)
		(stroke
			(width 0)
			(type default)
		)
	)
	(wire
		(pts
			(xy 298.45 72.39) (xy 318.77 72.39)
		)
		(stroke
			(width 0)
			(type default)
		)
	)
	(bus
		(pts
			(xy 295.91 105.41) (xy 295.91 107.95)
		)
		(stroke
			(width 0)
			(type default)
		)
	)
	(bus
		(pts
			(xy 77.47 132.08) (xy 78.74 132.08)
		)
		(stroke
			(width 0)
			(type default)
		)
	)
	(wire
		(pts
			(xy 118.11 170.18) (xy 118.11 176.53)
		)
		(stroke
			(width 0)
			(type default)
		)
	)
	(wire
		(pts
			(xy 298.45 120.65) (xy 318.77 120.65)
		)
		(stroke
			(width 0)
			(type default)
		)
	)
	(wire
		(pts
			(xy 81.28 134.62) (xy 93.98 134.62)
		)
		(stroke
			(width 0)
			(type default)
		)
	)
	(wire
		(pts
			(xy 316.23 191.77) (xy 318.77 191.77)
		)
		(stroke
			(width 0)
			(type default)
		)
	)
	(wire
		(pts
			(xy 313.69 184.15) (xy 318.77 184.15)
		)
		(stroke
			(width 0)
			(type default)
		)
	)
	(wire
		(pts
			(xy 93.98 134.62) (xy 93.98 137.16)
		)
		(stroke
			(width 0)
			(type default)
		)
	)
	(label "I_{2}C1.SCL"
		(at 299.72 166.37 0)
		(effects
			(font
				(size 1.27 1.27)
			)
			(justify left bottom)
		)
	)
	(label "CSI_5V"
		(at 275.59 184.15 180)
		(effects
			(font
				(size 1.27 1.27)
			)
			(justify right bottom)
		)
	)
	(label "CamCtrl.EN"
		(at 81.28 134.62 0)
		(effects
			(font
				(size 1.27 1.27)
			)
			(justify left bottom)
		)
	)
	(label "I_{2}C_CSI0.SDA"
		(at 299.72 158.75 0)
		(effects
			(font
				(size 1.27 1.27)
			)
			(justify left bottom)
		)
	)
	(label "CSI_3V3"
		(at 275.59 179.07 180)
		(effects
			(font
				(size 1.27 1.27)
			)
			(justify right bottom)
		)
	)
	(label "CSI0.CLK_N"
		(at 300.99 85.09 0)
		(effects
			(font
				(size 1.27 1.27)
			)
			(justify left bottom)
		)
	)
	(label "I_{2}C_CSI0.SCL"
		(at 299.72 161.29 0)
		(effects
			(font
				(size 1.27 1.27)
			)
			(justify left bottom)
		)
	)
	(label "CSI1.D3_P"
		(at 299.72 110.49 0)
		(effects
			(font
				(size 1.27 1.27)
			)
			(justify left bottom)
		)
	)
	(label "CSI0.D1_N"
		(at 300.99 72.39 0)
		(effects
			(font
				(size 1.27 1.27)
			)
			(justify left bottom)
		)
	)
	(label "CSI1.D0_P"
		(at 299.72 125.73 0)
		(effects
			(font
				(size 1.27 1.27)
			)
			(justify left bottom)
		)
	)
	(label "CSI0.CLK_P"
		(at 300.99 87.63 0)
		(effects
			(font
				(size 1.27 1.27)
			)
			(justify left bottom)
		)
	)
	(label "CSI1.D1_P"
		(at 299.72 120.65 0)
		(effects
			(font
				(size 1.27 1.27)
			)
			(justify left bottom)
		)
	)
	(label "CSI1.CLK_P"
		(at 299.72 133.35 0)
		(effects
			(font
				(size 1.27 1.27)
			)
			(justify left bottom)
		)
	)
	(label "CSI1.D2_P"
		(at 299.72 115.57 0)
		(effects
			(font
				(size 1.27 1.27)
			)
			(justify left bottom)
		)
	)
	(label "CSI1.D0_N"
		(at 299.72 123.19 0)
		(effects
			(font
				(size 1.27 1.27)
			)
			(justify left bottom)
		)
	)
	(label "CSI1.D3_N"
		(at 299.72 107.95 0)
		(effects
			(font
				(size 1.27 1.27)
			)
			(justify left bottom)
		)
	)
	(label "I_{2}C1.SDA"
		(at 299.72 163.83 0)
		(effects
			(font
				(size 1.27 1.27)
			)
			(justify left bottom)
		)
	)
	(label "CSI_3V3"
		(at 161.29 173.99 180)
		(effects
			(font
				(size 1.27 1.27)
			)
			(justify right bottom)
		)
	)
	(label "CamCtrl.VSYNC0"
		(at 299.72 140.97 0)
		(effects
			(font
				(size 1.27 1.27)
			)
			(justify left bottom)
		)
	)
	(label "CSI1.D1_N"
		(at 299.72 118.11 0)
		(effects
			(font
				(size 1.27 1.27)
			)
			(justify left bottom)
		)
	)
	(label "CamCtrl.VSYNC1"
		(at 299.72 146.05 0)
		(effects
			(font
				(size 1.27 1.27)
			)
			(justify left bottom)
		)
	)
	(label "CSI0.D0_N"
		(at 300.99 77.47 0)
		(effects
			(font
				(size 1.27 1.27)
			)
			(justify left bottom)
		)
	)
	(label "CSI0.D1_P"
		(at 300.99 74.93 0)
		(effects
			(font
				(size 1.27 1.27)
			)
			(justify left bottom)
		)
	)
	(label "CSI0.D0_P"
		(at 300.99 80.01 0)
		(effects
			(font
				(size 1.27 1.27)
			)
			(justify left bottom)
		)
	)
	(label "CSI1.D2_N"
		(at 299.72 113.03 0)
		(effects
			(font
				(size 1.27 1.27)
			)
			(justify left bottom)
		)
	)
	(label "CSI_5V"
		(at 161.29 129.54 180)
		(effects
			(font
				(size 1.27 1.27)
			)
			(justify right bottom)
		)
	)
	(label "CSI1.CLK_N"
		(at 299.72 130.81 0)
		(effects
			(font
				(size 1.27 1.27)
			)
			(justify left bottom)
		)
	)
	(hierarchical_label "I_{2}C1{I_{2}C}"
		(shape bidirectional)
		(at 293.37 160.02 180)
		(effects
			(font
				(size 1.27 1.27)
			)
			(justify right)
		)
	)
	(hierarchical_label "CamCtrl{CamCtrl}"
		(shape input)
		(at 293.37 137.16 180)
		(effects
			(font
				(size 1.27 1.27)
			)
			(justify right)
		)
	)
	(hierarchical_label "CamCtrl{CamCtrl}"
		(shape input)
		(at 77.47 132.08 180)
		(effects
			(font
				(size 1.27 1.27)
			)
			(justify right)
		)
	)
	(hierarchical_label "CSI1{CSI}"
		(shape bidirectional)
		(at 293.37 104.14 180)
		(effects
			(font
				(size 1.27 1.27)
			)
			(justify right)
		)
	)
	(hierarchical_label "I_{2}C_CSI0{I_{2}C}"
		(shape bidirectional)
		(at 293.37 154.94 180)
		(effects
			(font
				(size 1.27 1.27)
			)
			(justify right)
		)
	)
	(hierarchical_label "CSI0{CSI}"
		(shape bidirectional)
		(at 293.37 67.31 180)
		(effects
			(font
				(size 1.27 1.27)
			)
			(justify right)
		)
	)
	(symbol
		(lib_id "antmicroCapacitors0402:C_1u_0402")
		(at 307.34 191.77 90)
		(unit 1)
		(exclude_from_sim no)
		(in_bom yes)
		(on_board yes)
		(dnp no)
		(property "Reference" "C604"
			(at 307.975 187.325 90)
			(effects
				(font
					(size 1.27 1.27)
				)
				(justify right)
			)
		)
		(property "Value" "C_1u_0402"
			(at 317.5 171.45 0)
			(effects
				(font
					(size 1.27 1.27)
					(thickness 0.15)
				)
				(justify left bottom)
				(hide yes)
			)
		)
		(property "Footprint" "antmicro-footprints:C_0402_1005Metric"
			(at 320.04 171.45 0)
			(effects
				(font
					(size 1.27 1.27)
					(thickness 0.15)
				)
				(justify left bottom)
				(hide yes)
			)
		)
		(property "Datasheet" "https://product.tdk.com/en/search/capacitor/ceramic/mlcc/info?part_no=C1005X6S1A105K050BC"
			(at 322.58 171.45 0)
			(effects
				(font
					(size 1.27 1.27)
					(thickness 0.15)
				)
				(justify left bottom)
				(hide yes)
			)
		)
		(property "Description" ""
			(at 307.34 191.77 0)
			(effects
				(font
					(size 1.27 1.27)
				)
				(hide yes)
			)
		)
		(property "Manufacturer" "TDK"
			(at 327.66 171.45 0)
			(effects
				(font
					(size 1.27 1.27)
					(thickness 0.15)
				)
				(justify left bottom)
				(hide yes)
			)
		)
		(property "MPN" "C1005X6S1A105K050BC"
			(at 325.12 171.45 0)
			(effects
				(font
					(size 1.27 1.27)
					(thickness 0.15)
				)
				(justify left bottom)
				(hide yes)
			)
		)
		(property "Val" "1u"
			(at 307.975 191.135 90)
			(effects
				(font
					(size 1.27 1.27)
					(thickness 0.15)
				)
				(justify right)
			)
		)
		(property "License" "Apache-2.0"
			(at 330.2 171.45 0)
			(effects
				(font
					(size 1.27 1.27)
					(thickness 0.15)
				)
				(justify left bottom)
				(hide yes)
			)
		)
		(property "Author" "Antmicro"
			(at 332.74 171.45 0)
			(effects
				(font
					(size 1.27 1.27)
					(thickness 0.15)
				)
				(justify left bottom)
				(hide yes)
			)
		)
		(property "Voltage" ""
			(at 335.28 171.45 0)
			(effects
				(font
					(size 1.27 1.27)
				)
				(justify left bottom)
				(hide yes)
			)
		)
		(property "Dielectric" ""
			(at 337.82 171.45 0)
			(effects
				(font
					(size 1.27 1.27)
				)
				(justify left bottom)
				(hide yes)
			)
		)
		(pin "1"
		)
		(pin "2"
		)
		(instances
			(project "cm4-baseboard"
				(path ""
					(reference "C604")
					(unit 1)
				)
			)
		)
	)
	(symbol
		(lib_id "antmicroResistors0402:R_1k_0402")
		(at 152.4 135.89 90)
		(unit 1)
		(exclude_from_sim no)
		(in_bom yes)
		(on_board yes)
		(dnp no)
		(fields_autoplaced yes)
		(property "Reference" "R606"
			(at 154.94 132.08 90)
			(effects
				(font
					(size 1.27 1.27)
					(thickness 0.15)
				)
				(justify right)
			)
		)
		(property "Value" "R_1k_0402"
			(at 165.1 115.57 0)
			(effects
				(font
					(size 1.27 1.27)
					(thickness 0.15)
				)
				(justify left bottom)
				(hide yes)
			)
		)
		(property "Footprint" "antmicro-footprints:R_0402_1005Metric"
			(at 167.64 115.57 0)
			(effects
				(font
					(size 1.27 1.27)
					(thickness 0.15)
				)
				(justify left bottom)
				(hide yes)
			)
		)
		(property "Datasheet" "https://www.bourns.com/docs/product-datasheets/cr.pdf"
			(at 170.18 115.57 0)
			(effects
				(font
					(size 1.27 1.27)
					(thickness 0.15)
				)
				(justify left bottom)
				(hide yes)
			)
		)
		(property "Description" ""
			(at 152.4 135.89 0)
			(effects
				(font
					(size 1.27 1.27)
				)
				(hide yes)
			)
		)
		(property "MPN" "CR0402-FX-1001GLF"
			(at 172.72 115.57 0)
			(effects
				(font
					(size 1.27 1.27)
					(thickness 0.15)
				)
				(justify left bottom)
				(hide yes)
			)
		)
		(property "Manufacturer" "Bourns"
			(at 175.26 115.57 0)
			(effects
				(font
					(size 1.27 1.27)
					(thickness 0.15)
				)
				(justify left bottom)
				(hide yes)
			)
		)
		(property "License" "Apache-2.0"
			(at 177.8 115.57 0)
			(effects
				(font
					(size 1.27 1.27)
					(thickness 0.15)
				)
				(justify left bottom)
				(hide yes)
			)
		)
		(property "Author" "Antmicro"
			(at 180.34 115.57 0)
			(effects
				(font
					(size 1.27 1.27)
					(thickness 0.15)
				)
				(justify left bottom)
				(hide yes)
			)
		)
		(property "Val" "1k"
			(at 154.94 134.62 90)
			(effects
				(font
					(size 1.27 1.27)
					(thickness 0.15)
				)
				(justify right)
			)
		)
		(property "Tolerance" "1%"
			(at 162.56 115.57 0)
			(effects
				(font
					(size 1.27 1.27)
				)
				(justify left bottom)
				(hide yes)
			)
		)
		(pin "1"
		)
		(pin "2"
		)
		(instances
			(project "cm4-baseboard"
				(path ""
					(reference "R606")
					(unit 1)
				)
			)
		)
	)
	(symbol
		(lib_id "antmicroTestPoints:TP_0.75mm_SMD")
		(at 152.4 172.72 90)
		(unit 1)
		(exclude_from_sim no)
		(in_bom no)
		(on_board yes)
		(dnp no)
		(fields_autoplaced yes)
		(property "Reference" "TP604"
			(at 154.305 169.5449 90)
			(effects
				(font
					(size 1.27 1.27)
				)
				(justify right)
			)
		)
		(property "Value" "TP_0.75mm_SMD"
			(at 154.94 172.72 0)
			(effects
				(font
					(size 1.27 1.27)
					(thickness 0.15)
				)
				(justify left bottom)
				(hide yes)
			)
		)
		(property "Footprint" "antmicro-footprints:TP_SMD_0.75mm"
			(at 147.32 167.64 0)
			(effects
				(font
					(size 1.27 1.27)
					(thickness 0.15)
				)
				(justify left bottom)
				(hide yes)
			)
		)
		(property "Datasheet" ""
			(at 144.78 167.64 0)
			(effects
				(font
					(size 1.27 1.27)
					(thickness 0.15)
				)
				(justify left bottom)
				(hide yes)
			)
		)
		(property "Description" ""
			(at 152.4 172.72 0)
			(effects
				(font
					(size 1.27 1.27)
				)
				(hide yes)
			)
		)
		(property "MPN" ""
			(at 152.4 172.72 0)
			(effects
				(font
					(size 1.27 1.27)
					(thickness 0.15)
				)
				(justify left bottom)
				(hide yes)
			)
		)
		(property "Manufacturer" ""
			(at 152.4 172.72 0)
			(effects
				(font
					(size 1.27 1.27)
					(thickness 0.15)
				)
				(justify left bottom)
				(hide yes)
			)
		)
		(property "Author" "Antmicro"
			(at 167.64 157.48 0)
			(effects
				(font
					(size 1.27 1.27)
					(thickness 0.15)
				)
				(justify left bottom)
				(hide yes)
			)
		)
		(property "License" "Apache-2.0"
			(at 170.18 157.48 0)
			(effects
				(font
					(size 1.27 1.27)
					(thickness 0.15)
				)
				(justify left bottom)
				(hide yes)
			)
		)
		(pin "1"
		)
		(instances
			(project "cm4-baseboard"
				(path ""
					(reference "TP604")
					(unit 1)
				)
			)
		)
	)
	(symbol
		(lib_id "antmicropower:GND")
		(at 143.51 184.15 0)
		(unit 1)
		(exclude_from_sim no)
		(in_bom yes)
		(on_board yes)
		(dnp no)
		(fields_autoplaced yes)
		(property "Reference" "#PWR0609"
			(at 143.51 190.5 0)
			(effects
				(font
					(size 1.27 1.27)
				)
				(justify left bottom)
				(hide yes)
			)
		)
		(property "Value" "GND"
			(at 143.51 189.23 0)
			(effects
				(font
					(size 1.27 1.27)
				)
			)
		)
		(property "Footprint" ""
			(at 143.51 184.15 0)
			(effects
				(font
					(size 1.27 1.27)
				)
				(hide yes)
			)
		)
		(property "Datasheet" ""
			(at 143.51 184.15 0)
			(effects
				(font
					(size 1.27 1.27)
				)
				(hide yes)
			)
		)
		(property "Description" ""
			(at 143.51 184.15 0)
			(effects
				(font
					(size 1.27 1.27)
				)
				(hide yes)
			)
		)
		(property "Author" "Antmicro"
			(at 152.4 191.77 0)
			(effects
				(font
					(size 1.27 1.27)
					(thickness 0.15)
				)
				(justify left bottom)
				(hide yes)
			)
		)
		(property "License" "Apache-2.0"
			(at 152.4 194.31 0)
			(effects
				(font
					(size 1.27 1.27)
					(thickness 0.15)
				)
				(justify left bottom)
				(hide yes)
			)
		)
		(pin "1"
		)
		(instances
			(project "cm4-baseboard"
				(path ""
					(reference "#PWR0609")
					(unit 1)
				)
			)
		)
	)
	(symbol
		(lib_id "antmicropower:GND")
		(at 283.21 193.04 0)
		(unit 1)
		(exclude_from_sim no)
		(in_bom yes)
		(on_board yes)
		(dnp no)
		(fields_autoplaced yes)
		(property "Reference" "#PWR01"
			(at 292.1 195.58 0)
			(effects
				(font
					(size 1.27 1.27)
					(thickness 0.15)
				)
				(justify left bottom)
				(hide yes)
			)
		)
		(property "Value" "GND"
			(at 281.1998 198.12 0)
			(effects
				(font
					(size 1.27 1.27)
					(thickness 0.15)
				)
				(justify left bottom)
			)
		)
		(property "Footprint" ""
			(at 292.1 200.66 0)
			(effects
				(font
					(size 1.27 1.27)
					(thickness 0.15)
				)
				(justify left bottom)
				(hide yes)
			)
		)
		(property "Datasheet" ""
			(at 292.1 205.74 0)
			(effects
				(font
					(size 1.27 1.27)
					(thickness 0.15)
				)
				(justify left bottom)
				(hide yes)
			)
		)
		(property "Description" ""
			(at 283.21 193.04 0)
			(effects
				(font
					(size 1.27 1.27)
				)
				(hide yes)
			)
		)
		(property "Author" "Antmicro"
			(at 292.1 200.66 0)
			(effects
				(font
					(size 1.27 1.27)
					(thickness 0.15)
				)
				(justify left bottom)
				(hide yes)
			)
		)
		(property "License" "Apache-2.0"
			(at 292.1 203.2 0)
			(effects
				(font
					(size 1.27 1.27)
					(thickness 0.15)
				)
				(justify left bottom)
				(hide yes)
			)
		)
		(pin "1"
		)
		(instances
			(project "cm4-baseboard"
				(path ""
					(reference "#PWR01")
					(unit 1)
				)
			)
		)
	)
	(symbol
		(lib_id "antmicroResistors0402:R_10k_0402")
		(at 118.11 165.1 270)
		(unit 1)
		(exclude_from_sim no)
		(in_bom yes)
		(on_board yes)
		(dnp no)
		(property "Reference" "R603"
			(at 116.84 166.37 90)
			(effects
				(font
					(size 1.27 1.27)
				)
				(justify right)
			)
		)
		(property "Value" "R_10k_0402"
			(at 105.41 185.42 0)
			(effects
				(font
					(size 1.27 1.27)
					(thickness 0.15)
				)
				(justify left bottom)
				(hide yes)
			)
		)
		(property "Footprint" "antmicro-footprints:R_0402_1005Metric"
			(at 102.87 185.42 0)
			(effects
				(font
					(size 1.27 1.27)
					(thickness 0.15)
				)
				(justify left bottom)
				(hide yes)
			)
		)
		(property "Datasheet" "https://www.bourns.com/docs/product-datasheets/cr.pdf"
			(at 100.33 185.42 0)
			(effects
				(font
					(size 1.27 1.27)
					(thickness 0.15)
				)
				(justify left bottom)
				(hide yes)
			)
		)
		(property "Description" ""
			(at 118.11 165.1 0)
			(effects
				(font
					(size 1.27 1.27)
				)
				(hide yes)
			)
		)
		(property "Manufacturer" "Bourns"
			(at 95.25 185.42 0)
			(effects
				(font
					(size 1.27 1.27)
					(thickness 0.15)
				)
				(justify left bottom)
				(hide yes)
			)
		)
		(property "MPN" "CR0402-FX-1002GLF"
			(at 97.79 185.42 0)
			(effects
				(font
					(size 1.27 1.27)
					(thickness 0.15)
				)
				(justify left bottom)
				(hide yes)
			)
		)
		(property "Val" "10k"
			(at 116.84 168.91 90)
			(effects
				(font
					(size 1.27 1.27)
					(thickness 0.15)
				)
				(justify right)
			)
		)
		(property "License" "Apache-2.0"
			(at 92.71 185.42 0)
			(effects
				(font
					(size 1.27 1.27)
					(thickness 0.15)
				)
				(justify left bottom)
				(hide yes)
			)
		)
		(property "Author" "Antmicro"
			(at 90.17 185.42 0)
			(effects
				(font
					(size 1.27 1.27)
					(thickness 0.15)
				)
				(justify left bottom)
				(hide yes)
			)
		)
		(property "Tolerance" "1%"
			(at 107.95 185.42 0)
			(effects
				(font
					(size 1.27 1.27)
				)
				(justify left bottom)
				(hide yes)
			)
		)
		(pin "1"
		)
		(pin "2"
		)
		(instances
			(project "cm4-baseboard"
				(path ""
					(reference "R603")
					(unit 1)
				)
			)
		)
	)
	(symbol
		(lib_id "antmicroCapacitors0402:C_100n_0402")
		(at 109.22 165.1 90)
		(mirror x)
		(unit 1)
		(exclude_from_sim no)
		(in_bom yes)
		(on_board yes)
		(dnp no)
		(fields_autoplaced yes)
		(property "Reference" "C602"
			(at 106.68 166.3762 90)
			(effects
				(font
					(size 1.27 1.27)
				)
				(justify left)
			)
		)
		(property "Value" "C_100n_0402"
			(at 119.38 185.42 0)
			(effects
				(font
					(size 1.27 1.27)
					(thickness 0.15)
				)
				(justify left bottom)
				(hide yes)
			)
		)
		(property "Footprint" "antmicro-footprints:C_0402_1005Metric"
			(at 121.92 185.42 0)
			(effects
				(font
					(size 1.27 1.27)
					(thickness 0.15)
				)
				(justify left bottom)
				(hide yes)
			)
		)
		(property "Datasheet" "https://www.murata.com/products/productdetail?partno=GRM155R61H104KE14%23"
			(at 124.46 185.42 0)
			(effects
				(font
					(size 1.27 1.27)
					(thickness 0.15)
				)
				(justify left bottom)
				(hide yes)
			)
		)
		(property "Description" ""
			(at 109.22 165.1 0)
			(effects
				(font
					(size 1.27 1.27)
				)
				(hide yes)
			)
		)
		(property "Manufacturer" "Murata"
			(at 129.54 185.42 0)
			(effects
				(font
					(size 1.27 1.27)
					(thickness 0.15)
				)
				(justify left bottom)
				(hide yes)
			)
		)
		(property "MPN" "GRM155R61H104KE14D"
			(at 127 185.42 0)
			(effects
				(font
					(size 1.27 1.27)
					(thickness 0.15)
				)
				(justify left bottom)
				(hide yes)
			)
		)
		(property "Val" "100n"
			(at 106.68 168.9162 90)
			(effects
				(font
					(size 1.27 1.27)
					(thickness 0.15)
				)
				(justify left)
			)
		)
		(property "License" "Apache-2.0"
			(at 132.08 185.42 0)
			(effects
				(font
					(size 1.27 1.27)
					(thickness 0.15)
				)
				(justify left bottom)
				(hide yes)
			)
		)
		(property "Author" "Antmicro"
			(at 134.62 185.42 0)
			(effects
				(font
					(size 1.27 1.27)
					(thickness 0.15)
				)
				(justify left bottom)
				(hide yes)
			)
		)
		(property "Voltage" "50V"
			(at 137.16 185.42 0)
			(effects
				(font
					(size 1.27 1.27)
				)
				(justify left bottom)
				(hide yes)
			)
		)
		(property "Dielectric" "X5R"
			(at 139.7 185.42 0)
			(effects
				(font
					(size 1.27 1.27)
				)
				(justify left bottom)
				(hide yes)
			)
		)
		(pin "1"
		)
		(pin "2"
		)
		(instances
			(project "cm4-baseboard"
				(path ""
					(reference "C602")
					(unit 1)
				)
			)
		)
	)
	(symbol
		(lib_id "antmicropower:GND")
		(at 152.4 187.96 0)
		(unit 1)
		(exclude_from_sim no)
		(in_bom yes)
		(on_board yes)
		(dnp no)
		(property "Reference" "#PWR0611"
			(at 152.4 194.31 0)
			(effects
				(font
					(size 1.27 1.27)
				)
				(justify left bottom)
				(hide yes)
			)
		)
		(property "Value" "GND"
			(at 152.4 191.77 0)
			(effects
				(font
					(size 1.27 1.27)
				)
			)
		)
		(property "Footprint" ""
			(at 152.4 187.96 0)
			(effects
				(font
					(size 1.27 1.27)
				)
				(hide yes)
			)
		)
		(property "Datasheet" ""
			(at 152.4 187.96 0)
			(effects
				(font
					(size 1.27 1.27)
				)
				(hide yes)
			)
		)
		(property "Description" ""
			(at 152.4 187.96 0)
			(effects
				(font
					(size 1.27 1.27)
				)
				(hide yes)
			)
		)
		(property "Author" "Antmicro"
			(at 161.29 195.58 0)
			(effects
				(font
					(size 1.27 1.27)
					(thickness 0.15)
				)
				(justify left bottom)
				(hide yes)
			)
		)
		(property "License" "Apache-2.0"
			(at 161.29 198.12 0)
			(effects
				(font
					(size 1.27 1.27)
					(thickness 0.15)
				)
				(justify left bottom)
				(hide yes)
			)
		)
		(pin "1"
		)
		(instances
			(project "cm4-baseboard"
				(path ""
					(reference "#PWR0611")
					(unit 1)
				)
			)
		)
	)
	(symbol
		(lib_id "antmicropower:GND")
		(at 109.22 127 0)
		(mirror y)
		(unit 1)
		(exclude_from_sim no)
		(in_bom yes)
		(on_board yes)
		(dnp no)
		(property "Reference" "#PWR0603"
			(at 109.22 133.35 0)
			(effects
				(font
					(size 1.27 1.27)
				)
				(justify left bottom)
				(hide yes)
			)
		)
		(property "Value" "GND"
			(at 105.41 128.27 0)
			(effects
				(font
					(size 1.27 1.27)
				)
			)
		)
		(property "Footprint" ""
			(at 109.22 127 0)
			(effects
				(font
					(size 1.27 1.27)
				)
				(hide yes)
			)
		)
		(property "Datasheet" ""
			(at 109.22 127 0)
			(effects
				(font
					(size 1.27 1.27)
				)
				(hide yes)
			)
		)
		(property "Description" ""
			(at 109.22 127 0)
			(effects
				(font
					(size 1.27 1.27)
				)
				(hide yes)
			)
		)
		(property "Author" "Antmicro"
			(at 100.33 134.62 0)
			(effects
				(font
					(size 1.27 1.27)
					(thickness 0.15)
				)
				(justify left bottom)
				(hide yes)
			)
		)
		(property "License" "Apache-2.0"
			(at 100.33 137.16 0)
			(effects
				(font
					(size 1.27 1.27)
					(thickness 0.15)
				)
				(justify left bottom)
				(hide yes)
			)
		)
		(pin "1"
		)
		(instances
			(project "cm4-baseboard"
				(path ""
					(reference "#PWR0603")
					(unit 1)
				)
			)
		)
	)
	(symbol
		(lib_id "antmicroResistors0402:R_4k7_0402")
		(at 143.51 182.88 90)
		(unit 1)
		(exclude_from_sim no)
		(in_bom yes)
		(on_board yes)
		(dnp no)
		(property "Reference" "R605"
			(at 144.78 179.07 90)
			(effects
				(font
					(size 1.27 1.27)
				)
				(justify right)
			)
		)
		(property "Value" "R_4k7_0402"
			(at 156.21 162.56 0)
			(effects
				(font
					(size 1.27 1.27)
					(thickness 0.15)
				)
				(justify left bottom)
				(hide yes)
			)
		)
		(property "Footprint" "antmicro-footprints:R_0402_1005Metric"
			(at 158.75 162.56 0)
			(effects
				(font
					(size 1.27 1.27)
					(thickness 0.15)
				)
				(justify left bottom)
				(hide yes)
			)
		)
		(property "Datasheet" "https://www.bourns.com/docs/product-datasheets/cr.pdf"
			(at 161.29 162.56 0)
			(effects
				(font
					(size 1.27 1.27)
					(thickness 0.15)
				)
				(justify left bottom)
				(hide yes)
			)
		)
		(property "Description" ""
			(at 143.51 182.88 0)
			(effects
				(font
					(size 1.27 1.27)
				)
				(hide yes)
			)
		)
		(property "Manufacturer" "Bourns"
			(at 166.37 162.56 0)
			(effects
				(font
					(size 1.27 1.27)
					(thickness 0.15)
				)
				(justify left bottom)
				(hide yes)
			)
		)
		(property "MPN" "CR0402-FX-4701GLF"
			(at 163.83 162.56 0)
			(effects
				(font
					(size 1.27 1.27)
					(thickness 0.15)
				)
				(justify left bottom)
				(hide yes)
			)
		)
		(property "Val" "4k7"
			(at 144.78 181.61 90)
			(effects
				(font
					(size 1.27 1.27)
					(thickness 0.15)
				)
				(justify right)
			)
		)
		(property "License" "Apache-2.0"
			(at 168.91 162.56 0)
			(effects
				(font
					(size 1.27 1.27)
					(thickness 0.15)
				)
				(justify left bottom)
				(hide yes)
			)
		)
		(property "Author" "Antmicro"
			(at 171.45 162.56 0)
			(effects
				(font
					(size 1.27 1.27)
					(thickness 0.15)
				)
				(justify left bottom)
				(hide yes)
			)
		)
		(property "Tolerance" "1%"
			(at 153.67 162.56 0)
			(effects
				(font
					(size 1.27 1.27)
				)
				(justify left bottom)
				(hide yes)
			)
		)
		(pin "1"
		)
		(pin "2"
		)
		(instances
			(project "cm4-baseboard"
				(path ""
					(reference "R605")
					(unit 1)
				)
			)
		)
	)
	(symbol
		(lib_id "antmicroResistors0402:R_4k7_0402")
		(at 143.51 138.43 90)
		(unit 1)
		(exclude_from_sim no)
		(in_bom yes)
		(on_board yes)
		(dnp no)
		(property "Reference" "R604"
			(at 144.78 134.62 90)
			(effects
				(font
					(size 1.27 1.27)
				)
				(justify right)
			)
		)
		(property "Value" "R_4k7_0402"
			(at 156.21 118.11 0)
			(effects
				(font
					(size 1.27 1.27)
					(thickness 0.15)
				)
				(justify left bottom)
				(hide yes)
			)
		)
		(property "Footprint" "antmicro-footprints:R_0402_1005Metric"
			(at 158.75 118.11 0)
			(effects
				(font
					(size 1.27 1.27)
					(thickness 0.15)
				)
				(justify left bottom)
				(hide yes)
			)
		)
		(property "Datasheet" "https://www.bourns.com/docs/product-datasheets/cr.pdf"
			(at 161.29 118.11 0)
			(effects
				(font
					(size 1.27 1.27)
					(thickness 0.15)
				)
				(justify left bottom)
				(hide yes)
			)
		)
		(property "Description" ""
			(at 143.51 138.43 0)
			(effects
				(font
					(size 1.27 1.27)
				)
				(hide yes)
			)
		)
		(property "Manufacturer" "Bourns"
			(at 166.37 118.11 0)
			(effects
				(font
					(size 1.27 1.27)
					(thickness 0.15)
				)
				(justify left bottom)
				(hide yes)
			)
		)
		(property "MPN" "CR0402-FX-4701GLF"
			(at 163.83 118.11 0)
			(effects
				(font
					(size 1.27 1.27)
					(thickness 0.15)
				)
				(justify left bottom)
				(hide yes)
			)
		)
		(property "Val" "4k7"
			(at 144.78 137.16 90)
			(effects
				(font
					(size 1.27 1.27)
					(thickness 0.15)
				)
				(justify right)
			)
		)
		(property "License" "Apache-2.0"
			(at 168.91 118.11 0)
			(effects
				(font
					(size 1.27 1.27)
					(thickness 0.15)
				)
				(justify left bottom)
				(hide yes)
			)
		)
		(property "Author" "Antmicro"
			(at 171.45 118.11 0)
			(effects
				(font
					(size 1.27 1.27)
					(thickness 0.15)
				)
				(justify left bottom)
				(hide yes)
			)
		)
		(property "Tolerance" "1%"
			(at 153.67 118.11 0)
			(effects
				(font
					(size 1.27 1.27)
				)
				(justify left bottom)
				(hide yes)
			)
		)
		(pin "1"
		)
		(pin "2"
		)
		(instances
			(project "cm4-baseboard"
				(path ""
					(reference "R604")
					(unit 1)
				)
			)
		)
	)
	(symbol
		(lib_id "antmicroTVSDiodes:PESD5Z5_0F")
		(at 278.13 186.69 90)
		(mirror x)
		(unit 1)
		(exclude_from_sim no)
		(in_bom yes)
		(on_board yes)
		(dnp no)
		(property "Reference" "D603"
			(at 276.86 187.96 90)
			(effects
				(font
					(size 1.27 1.27)
					(thickness 0.15)
				)
				(justify left)
			)
		)
		(property "Value" "PESD5Z5_0F"
			(at 275.59 189.5475 90)
			(effects
				(font
					(size 1.27 1.27)
					(thickness 0.15)
				)
				(justify left)
				(hide yes)
			)
		)
		(property "Footprint" "antmicro-footprints:SOD-523"
			(at 283.21 201.93 0)
			(effects
				(font
					(size 1.27 1.27)
					(thickness 0.15)
				)
				(justify left bottom)
				(hide yes)
			)
		)
		(property "Datasheet" "https://assets.nexperia.com/documents/data-sheet/PESD5Z5_0.pdf"
			(at 285.75 201.93 0)
			(effects
				(font
					(size 1.27 1.27)
					(thickness 0.15)
				)
				(justify left bottom)
				(hide yes)
			)
		)
		(property "Description" ""
			(at 278.13 186.69 0)
			(effects
				(font
					(size 1.27 1.27)
				)
				(hide yes)
			)
		)
		(property "Manufacturer" "Nexperia"
			(at 288.29 201.93 0)
			(effects
				(font
					(size 1.27 1.27)
					(thickness 0.15)
				)
				(justify left bottom)
				(hide yes)
			)
		)
		(property "MPN" "PESD5Z5.0F"
			(at 276.86 190.5 90)
			(effects
				(font
					(size 1.27 1.27)
					(thickness 0.15)
				)
				(justify left)
			)
		)
		(property "Author" "Antmicro"
			(at 293.37 201.93 0)
			(effects
				(font
					(size 1.27 1.27)
					(thickness 0.15)
				)
				(justify left bottom)
				(hide yes)
			)
		)
		(property "License" "Apache-2.0"
			(at 295.91 201.93 0)
			(effects
				(font
					(size 1.27 1.27)
					(thickness 0.15)
				)
				(justify left bottom)
				(hide yes)
			)
		)
		(pin "2"
		)
		(pin "1"
		)
		(instances
			(project "cm4-baseboard"
				(path ""
					(reference "D603")
					(unit 1)
				)
			)
		)
	)
	(symbol
		(lib_id "antmicroFCCConnectors:Conn_FFC_WE_68715014522")
		(at 318.77 62.23 0)
		(unit 1)
		(exclude_from_sim no)
		(in_bom yes)
		(on_board yes)
		(dnp no)
		(property "Reference" "J601"
			(at 318.77 55.88 0)
			(effects
				(font
					(size 1.27 1.27)
				)
				(justify left)
			)
		)
		(property "Value" "Conn_FFC_WE_68715014522"
			(at 327.66 128.905 0)
			(effects
				(font
					(size 1.27 1.27)
					(thickness 0.15)
				)
				(justify left)
				(hide yes)
			)
		)
		(property "Footprint" "antmicro-footprints:Conn_FFC_WE_68715014x22"
			(at 337.82 72.39 0)
			(effects
				(font
					(size 1.27 1.27)
					(thickness 0.15)
				)
				(justify left bottom)
				(hide yes)
			)
		)
		(property "Datasheet" "https://www.we-online.com/components/products/datasheet/68715014522.pdf"
			(at 337.82 74.93 0)
			(effects
				(font
					(size 1.27 1.27)
					(thickness 0.15)
				)
				(justify left bottom)
				(hide yes)
			)
		)
		(property "Description" ""
			(at 318.77 62.23 0)
			(effects
				(font
					(size 1.27 1.27)
				)
				(hide yes)
			)
		)
		(property "MPN" "68715014522"
			(at 318.77 58.42 0)
			(effects
				(font
					(size 1.27 1.27)
					(thickness 0.15)
				)
				(justify left)
			)
		)
		(property "Manufacturer" "Würth Elektronik"
			(at 337.82 80.01 0)
			(effects
				(font
					(size 1.27 1.27)
					(thickness 0.15)
				)
				(justify left bottom)
				(hide yes)
			)
		)
		(property "Author" "Antmicro"
			(at 337.82 82.55 0)
			(effects
				(font
					(size 1.27 1.27)
					(thickness 0.15)
				)
				(justify left bottom)
				(hide yes)
			)
		)
		(property "License" "Apache-2.0"
			(at 337.82 85.09 0)
			(effects
				(font
					(size 1.27 1.27)
					(thickness 0.15)
				)
				(justify left bottom)
				(hide yes)
			)
		)
		(pin "1"
		)
		(pin "10"
		)
		(pin "11"
		)
		(pin "12"
		)
		(pin "13"
		)
		(pin "14"
		)
		(pin "15"
		)
		(pin "16"
		)
		(pin "17"
		)
		(pin "18"
		)
		(pin "19"
		)
		(pin "2"
		)
		(pin "20"
		)
		(pin "21"
		)
		(pin "22"
		)
		(pin "23"
		)
		(pin "24"
		)
		(pin "25"
		)
		(pin "26"
		)
		(pin "27"
		)
		(pin "28"
		)
		(pin "29"
		)
		(pin "3"
		)
		(pin "30"
		)
		(pin "31"
		)
		(pin "32"
		)
		(pin "33"
		)
		(pin "34"
		)
		(pin "35"
		)
		(pin "36"
		)
		(pin "37"
		)
		(pin "38"
		)
		(pin "39"
		)
		(pin "4"
		)
		(pin "40"
		)
		(pin "41"
		)
		(pin "42"
		)
		(pin "43"
		)
		(pin "44"
		)
		(pin "45"
		)
		(pin "46"
		)
		(pin "47"
		)
		(pin "48"
		)
		(pin "49"
		)
		(pin "5"
		)
		(pin "50"
		)
		(pin "6"
		)
		(pin "7"
		)
		(pin "8"
		)
		(pin "9"
		)
		(pin "MP1"
		)
		(pin "MP2"
		)
		(instances
			(project "cm4-baseboard"
				(path ""
					(reference "J601")
					(unit 1)
				)
			)
		)
	)
	(symbol
		(lib_id "antmicroCapacitors0402:C_100n_0402")
		(at 109.22 120.65 90)
		(mirror x)
		(unit 1)
		(exclude_from_sim no)
		(in_bom yes)
		(on_board yes)
		(dnp no)
		(fields_autoplaced yes)
		(property "Reference" "C601"
			(at 106.68 121.9262 90)
			(effects
				(font
					(size 1.27 1.27)
				)
				(justify left)
			)
		)
		(property "Value" "C_100n_0402"
			(at 119.38 140.97 0)
			(effects
				(font
					(size 1.27 1.27)
					(thickness 0.15)
				)
				(justify left bottom)
				(hide yes)
			)
		)
		(property "Footprint" "antmicro-footprints:C_0402_1005Metric"
			(at 121.92 140.97 0)
			(effects
				(font
					(size 1.27 1.27)
					(thickness 0.15)
				)
				(justify left bottom)
				(hide yes)
			)
		)
		(property "Datasheet" "https://www.murata.com/products/productdetail?partno=GRM155R61H104KE14%23"
			(at 124.46 140.97 0)
			(effects
				(font
					(size 1.27 1.27)
					(thickness 0.15)
				)
				(justify left bottom)
				(hide yes)
			)
		)
		(property "Description" ""
			(at 109.22 120.65 0)
			(effects
				(font
					(size 1.27 1.27)
				)
				(hide yes)
			)
		)
		(property "Manufacturer" "Murata"
			(at 129.54 140.97 0)
			(effects
				(font
					(size 1.27 1.27)
					(thickness 0.15)
				)
				(justify left bottom)
				(hide yes)
			)
		)
		(property "MPN" "GRM155R61H104KE14D"
			(at 127 140.97 0)
			(effects
				(font
					(size 1.27 1.27)
					(thickness 0.15)
				)
				(justify left bottom)
				(hide yes)
			)
		)
		(property "Val" "100n"
			(at 106.68 124.4662 90)
			(effects
				(font
					(size 1.27 1.27)
					(thickness 0.15)
				)
				(justify left)
			)
		)
		(property "License" "Apache-2.0"
			(at 132.08 140.97 0)
			(effects
				(font
					(size 1.27 1.27)
					(thickness 0.15)
				)
				(justify left bottom)
				(hide yes)
			)
		)
		(property "Author" "Antmicro"
			(at 134.62 140.97 0)
			(effects
				(font
					(size 1.27 1.27)
					(thickness 0.15)
				)
				(justify left bottom)
				(hide yes)
			)
		)
		(property "Voltage" "50V"
			(at 137.16 140.97 0)
			(effects
				(font
					(size 1.27 1.27)
				)
				(justify left bottom)
				(hide yes)
			)
		)
		(property "Dielectric" "X5R"
			(at 139.7 140.97 0)
			(effects
				(font
					(size 1.27 1.27)
				)
				(justify left bottom)
				(hide yes)
			)
		)
		(pin "1"
		)
		(pin "2"
		)
		(instances
			(project "cm4-baseboard"
				(path ""
					(reference "C601")
					(unit 1)
				)
			)
		)
	)
	(symbol
		(lib_id "antmicropower:GND")
		(at 109.22 171.45 0)
		(mirror y)
		(unit 1)
		(exclude_from_sim no)
		(in_bom yes)
		(on_board yes)
		(dnp no)
		(property "Reference" "#PWR0605"
			(at 109.22 177.8 0)
			(effects
				(font
					(size 1.27 1.27)
				)
				(justify left bottom)
				(hide yes)
			)
		)
		(property "Value" "GND"
			(at 105.41 172.72 0)
			(effects
				(font
					(size 1.27 1.27)
				)
			)
		)
		(property "Footprint" ""
			(at 109.22 171.45 0)
			(effects
				(font
					(size 1.27 1.27)
				)
				(hide yes)
			)
		)
		(property "Datasheet" ""
			(at 109.22 171.45 0)
			(effects
				(font
					(size 1.27 1.27)
				)
				(hide yes)
			)
		)
		(property "Description" ""
			(at 109.22 171.45 0)
			(effects
				(font
					(size 1.27 1.27)
				)
				(hide yes)
			)
		)
		(property "Author" "Antmicro"
			(at 100.33 179.07 0)
			(effects
				(font
					(size 1.27 1.27)
					(thickness 0.15)
				)
				(justify left bottom)
				(hide yes)
			)
		)
		(property "License" "Apache-2.0"
			(at 100.33 181.61 0)
			(effects
				(font
					(size 1.27 1.27)
					(thickness 0.15)
				)
				(justify left bottom)
				(hide yes)
			)
		)
		(pin "1"
		)
		(instances
			(project "cm4-baseboard"
				(path ""
					(reference "#PWR0605")
					(unit 1)
				)
			)
		)
	)
	(symbol
		(lib_id "antmicroCapacitors0402:C_1u_0402")
		(at 299.72 191.77 90)
		(unit 1)
		(exclude_from_sim no)
		(in_bom yes)
		(on_board yes)
		(dnp no)
		(property "Reference" "C603"
			(at 300.355 187.325 90)
			(effects
				(font
					(size 1.27 1.27)
				)
				(justify right)
			)
		)
		(property "Value" "C_1u_0402"
			(at 309.88 171.45 0)
			(effects
				(font
					(size 1.27 1.27)
					(thickness 0.15)
				)
				(justify left bottom)
				(hide yes)
			)
		)
		(property "Footprint" "antmicro-footprints:C_0402_1005Metric"
			(at 312.42 171.45 0)
			(effects
				(font
					(size 1.27 1.27)
					(thickness 0.15)
				)
				(justify left bottom)
				(hide yes)
			)
		)
		(property "Datasheet" "https://product.tdk.com/en/search/capacitor/ceramic/mlcc/info?part_no=C1005X6S1A105K050BC"
			(at 314.96 171.45 0)
			(effects
				(font
					(size 1.27 1.27)
					(thickness 0.15)
				)
				(justify left bottom)
				(hide yes)
			)
		)
		(property "Description" ""
			(at 299.72 191.77 0)
			(effects
				(font
					(size 1.27 1.27)
				)
				(hide yes)
			)
		)
		(property "Manufacturer" "TDK"
			(at 320.04 171.45 0)
			(effects
				(font
					(size 1.27 1.27)
					(thickness 0.15)
				)
				(justify left bottom)
				(hide yes)
			)
		)
		(property "MPN" "C1005X6S1A105K050BC"
			(at 317.5 171.45 0)
			(effects
				(font
					(size 1.27 1.27)
					(thickness 0.15)
				)
				(justify left bottom)
				(hide yes)
			)
		)
		(property "Val" "1u"
			(at 300.355 191.135 90)
			(effects
				(font
					(size 1.27 1.27)
					(thickness 0.15)
				)
				(justify right)
			)
		)
		(property "License" "Apache-2.0"
			(at 322.58 171.45 0)
			(effects
				(font
					(size 1.27 1.27)
					(thickness 0.15)
				)
				(justify left bottom)
				(hide yes)
			)
		)
		(property "Author" "Antmicro"
			(at 325.12 171.45 0)
			(effects
				(font
					(size 1.27 1.27)
					(thickness 0.15)
				)
				(justify left bottom)
				(hide yes)
			)
		)
		(property "Voltage" ""
			(at 327.66 171.45 0)
			(effects
				(font
					(size 1.27 1.27)
				)
				(justify left bottom)
				(hide yes)
			)
		)
		(property "Dielectric" ""
			(at 330.2 171.45 0)
			(effects
				(font
					(size 1.27 1.27)
				)
				(justify left bottom)
				(hide yes)
			)
		)
		(pin "1"
		)
		(pin "2"
		)
		(instances
			(project "cm4-baseboard"
				(path ""
					(reference "C603")
					(unit 1)
				)
			)
		)
	)
	(symbol
		(lib_id "antmicropower:GND")
		(at 307.34 193.04 0)
		(unit 1)
		(exclude_from_sim no)
		(in_bom yes)
		(on_board yes)
		(dnp no)
		(property "Reference" "#PWR0613"
			(at 307.34 199.39 0)
			(effects
				(font
					(size 1.27 1.27)
				)
				(justify left bottom)
				(hide yes)
			)
		)
		(property "Value" "GND"
			(at 307.34 196.85 0)
			(effects
				(font
					(size 1.27 1.27)
				)
			)
		)
		(property "Footprint" ""
			(at 307.34 193.04 0)
			(effects
				(font
					(size 1.27 1.27)
				)
				(hide yes)
			)
		)
		(property "Datasheet" ""
			(at 307.34 193.04 0)
			(effects
				(font
					(size 1.27 1.27)
				)
				(hide yes)
			)
		)
		(property "Description" ""
			(at 307.34 193.04 0)
			(effects
				(font
					(size 1.27 1.27)
				)
				(hide yes)
			)
		)
		(property "Author" "Antmicro"
			(at 316.23 200.66 0)
			(effects
				(font
					(size 1.27 1.27)
					(thickness 0.15)
				)
				(justify left bottom)
				(hide yes)
			)
		)
		(property "License" "Apache-2.0"
			(at 316.23 203.2 0)
			(effects
				(font
					(size 1.27 1.27)
					(thickness 0.15)
				)
				(justify left bottom)
				(hide yes)
			)
		)
		(pin "1"
		)
		(instances
			(project "cm4-baseboard"
				(path ""
					(reference "#PWR0613")
					(unit 1)
				)
			)
		)
	)
	(symbol
		(lib_id "antmicroPMICPowerDistributionSwitchesLoadDrivers:AP22615A_TSOT26")
		(at 121.92 129.54 0)
		(unit 1)
		(exclude_from_sim no)
		(in_bom yes)
		(on_board yes)
		(dnp no)
		(property "Reference" "U601"
			(at 129.54 123.19 0)
			(effects
				(font
					(size 1.27 1.27)
				)
			)
		)
		(property "Value" "AP22615A_TSOT26"
			(at 129.54 125.73 0)
			(effects
				(font
					(size 1.27 1.27)
					(thickness 0.15)
				)
				(hide yes)
			)
		)
		(property "Footprint" "antmicro-footprints:TSOT23-6"
			(at 152.4 137.16 0)
			(effects
				(font
					(size 1.27 1.27)
					(thickness 0.15)
				)
				(justify left bottom)
				(hide yes)
			)
		)
		(property "Datasheet" "https://www.mouser.com/datasheet/2/115/DIOD_S_A0008958405_1-2543193.pdf"
			(at 152.4 139.7 0)
			(effects
				(font
					(size 1.27 1.27)
					(thickness 0.15)
				)
				(justify left bottom)
				(hide yes)
			)
		)
		(property "Description" ""
			(at 121.92 129.54 0)
			(effects
				(font
					(size 1.27 1.27)
				)
				(hide yes)
			)
		)
		(property "MPN" "AP22615AWU-7"
			(at 129.54 125.73 0)
			(effects
				(font
					(size 1.27 1.27)
					(thickness 0.15)
				)
			)
		)
		(property "Manufacturer" "Diodes Incorporated"
			(at 152.4 144.78 0)
			(effects
				(font
					(size 1.27 1.27)
					(thickness 0.15)
				)
				(justify left bottom)
				(hide yes)
			)
		)
		(property "Author" "Antmicro"
			(at 152.4 147.32 0)
			(effects
				(font
					(size 1.27 1.27)
					(thickness 0.15)
				)
				(justify left bottom)
				(hide yes)
			)
		)
		(property "License" "Apache-2.0"
			(at 152.4 149.86 0)
			(effects
				(font
					(size 1.27 1.27)
					(thickness 0.15)
				)
				(justify left bottom)
				(hide yes)
			)
		)
		(pin "1"
		)
		(pin "2"
		)
		(pin "3"
		)
		(pin "4"
		)
		(pin "5"
		)
		(pin "6"
		)
		(instances
			(project "cm4-baseboard"
				(path ""
					(reference "U601")
					(unit 1)
				)
			)
		)
	)
	(symbol
		(lib_id "antmicropower:GND")
		(at 152.4 143.51 0)
		(unit 1)
		(exclude_from_sim no)
		(in_bom yes)
		(on_board yes)
		(dnp no)
		(property "Reference" "#PWR0610"
			(at 152.4 149.86 0)
			(effects
				(font
					(size 1.27 1.27)
				)
				(justify left bottom)
				(hide yes)
			)
		)
		(property "Value" "GND"
			(at 154.305 147.32 0)
			(effects
				(font
					(size 1.27 1.27)
				)
				(justify right)
			)
		)
		(property "Footprint" ""
			(at 152.4 143.51 0)
			(effects
				(font
					(size 1.27 1.27)
				)
				(hide yes)
			)
		)
		(property "Datasheet" ""
			(at 152.4 143.51 0)
			(effects
				(font
					(size 1.27 1.27)
				)
				(hide yes)
			)
		)
		(property "Description" ""
			(at 152.4 143.51 0)
			(effects
				(font
					(size 1.27 1.27)
				)
				(hide yes)
			)
		)
		(property "Author" "Antmicro"
			(at 161.29 151.13 0)
			(effects
				(font
					(size 1.27 1.27)
					(thickness 0.15)
				)
				(justify left bottom)
				(hide yes)
			)
		)
		(property "License" "Apache-2.0"
			(at 161.29 153.67 0)
			(effects
				(font
					(size 1.27 1.27)
					(thickness 0.15)
				)
				(justify left bottom)
				(hide yes)
			)
		)
		(pin "1"
		)
		(instances
			(project "cm4-baseboard"
				(path ""
					(reference "#PWR0610")
					(unit 1)
				)
			)
		)
	)
	(symbol
		(lib_id "antmicropower:+3V3")
		(at 109.22 162.56 0)
		(unit 1)
		(exclude_from_sim no)
		(in_bom yes)
		(on_board yes)
		(dnp no)
		(property "Reference" "#PWR0604"
			(at 109.22 166.37 0)
			(effects
				(font
					(size 1.27 1.27)
				)
				(justify left bottom)
				(hide yes)
			)
		)
		(property "Value" "+3V3"
			(at 106.68 158.75 0)
			(effects
				(font
					(size 1.27 1.27)
				)
				(justify left)
			)
		)
		(property "Footprint" ""
			(at 109.22 162.56 0)
			(effects
				(font
					(size 1.27 1.27)
				)
				(hide yes)
			)
		)
		(property "Datasheet" ""
			(at 109.22 162.56 0)
			(effects
				(font
					(size 1.27 1.27)
				)
				(hide yes)
			)
		)
		(property "Description" ""
			(at 109.22 162.56 0)
			(effects
				(font
					(size 1.27 1.27)
				)
				(hide yes)
			)
		)
		(property "Author" "Antmicro"
			(at 124.46 165.1 0)
			(effects
				(font
					(size 1.27 1.27)
					(thickness 0.15)
				)
				(justify left bottom)
				(hide yes)
			)
		)
		(property "License" "Apache-2.0"
			(at 124.46 167.64 0)
			(effects
				(font
					(size 1.27 1.27)
					(thickness 0.15)
				)
				(justify left bottom)
				(hide yes)
			)
		)
		(pin "1"
		)
		(instances
			(project "cm4-baseboard"
				(path ""
					(reference "#PWR0604")
					(unit 1)
				)
			)
		)
	)
	(symbol
		(lib_id "antmicroTVSDiodes:PESD5Z5_0F")
		(at 283.21 186.69 90)
		(mirror x)
		(unit 1)
		(exclude_from_sim no)
		(in_bom yes)
		(on_board yes)
		(dnp no)
		(property "Reference" "D604"
			(at 284.48 187.96 90)
			(effects
				(font
					(size 1.27 1.27)
					(thickness 0.15)
				)
				(justify right)
			)
		)
		(property "Value" "PESD5Z5_0F"
			(at 285.75 189.5475 90)
			(effects
				(font
					(size 1.27 1.27)
					(thickness 0.15)
				)
				(justify right)
				(hide yes)
			)
		)
		(property "Footprint" "antmicro-footprints:SOD-523"
			(at 288.29 201.93 0)
			(effects
				(font
					(size 1.27 1.27)
					(thickness 0.15)
				)
				(justify left bottom)
				(hide yes)
			)
		)
		(property "Datasheet" "https://assets.nexperia.com/documents/data-sheet/PESD5Z5_0.pdf"
			(at 290.83 201.93 0)
			(effects
				(font
					(size 1.27 1.27)
					(thickness 0.15)
				)
				(justify left bottom)
				(hide yes)
			)
		)
		(property "Description" ""
			(at 283.21 186.69 0)
			(effects
				(font
					(size 1.27 1.27)
				)
				(hide yes)
			)
		)
		(property "Manufacturer" "Nexperia"
			(at 293.37 201.93 0)
			(effects
				(font
					(size 1.27 1.27)
					(thickness 0.15)
				)
				(justify left bottom)
				(hide yes)
			)
		)
		(property "MPN" "PESD5Z5.0F"
			(at 284.48 190.5 90)
			(effects
				(font
					(size 1.27 1.27)
					(thickness 0.15)
				)
				(justify right)
			)
		)
		(property "Author" "Antmicro"
			(at 298.45 201.93 0)
			(effects
				(font
					(size 1.27 1.27)
					(thickness 0.15)
				)
				(justify left bottom)
				(hide yes)
			)
		)
		(property "License" "Apache-2.0"
			(at 300.99 201.93 0)
			(effects
				(font
					(size 1.27 1.27)
					(thickness 0.15)
				)
				(justify left bottom)
				(hide yes)
			)
		)
		(pin "2"
		)
		(pin "1"
		)
		(instances
			(project "cm4-baseboard"
				(path ""
					(reference "D604")
					(unit 1)
				)
			)
		)
	)
	(symbol
		(lib_id "antmicroTestPoints:TP_0.75mm_SMD")
		(at 116.84 176.53 0)
		(mirror y)
		(unit 1)
		(exclude_from_sim no)
		(in_bom no)
		(on_board yes)
		(dnp no)
		(fields_autoplaced yes)
		(property "Reference" "TP602"
			(at 111.76 176.5299 0)
			(effects
				(font
					(size 1.27 1.27)
				)
				(justify left)
			)
		)
		(property "Value" "TP_0.75mm_SMD"
			(at 101.6 184.15 0)
			(effects
				(font
					(size 1.27 1.27)
					(thickness 0.15)
				)
				(justify left bottom)
				(hide yes)
			)
		)
		(property "Footprint" "antmicro-footprints:TP_SMD_0.75mm"
			(at 101.6 186.69 0)
			(effects
				(font
					(size 1.27 1.27)
					(thickness 0.15)
				)
				(justify left bottom)
				(hide yes)
			)
		)
		(property "Datasheet" ""
			(at 101.6 189.23 0)
			(effects
				(font
					(size 1.27 1.27)
					(thickness 0.15)
				)
				(justify left bottom)
				(hide yes)
			)
		)
		(property "Description" ""
			(at 116.84 176.53 0)
			(effects
				(font
					(size 1.27 1.27)
				)
				(hide yes)
			)
		)
		(property "MPN" ""
			(at 116.84 176.53 0)
			(effects
				(font
					(size 1.27 1.27)
				)
				(hide yes)
			)
		)
		(property "Manufacturer" ""
			(at 116.84 176.53 0)
			(effects
				(font
					(size 1.27 1.27)
				)
				(hide yes)
			)
		)
		(property "Author" "Antmicro"
			(at 101.6 191.77 0)
			(effects
				(font
					(size 1.27 1.27)
					(thickness 0.15)
				)
				(justify left bottom)
				(hide yes)
			)
		)
		(property "License" "Apache-2.0"
			(at 101.6 194.31 0)
			(effects
				(font
					(size 1.27 1.27)
					(thickness 0.15)
				)
				(justify left bottom)
				(hide yes)
			)
		)
		(pin "1"
		)
		(instances
			(project "cm4-baseboard"
				(path ""
					(reference "TP602")
					(unit 1)
				)
			)
		)
	)
	(symbol
		(lib_id "antmicropower:GND")
		(at 138.43 139.7 0)
		(unit 1)
		(exclude_from_sim no)
		(in_bom yes)
		(on_board yes)
		(dnp no)
		(fields_autoplaced yes)
		(property "Reference" "#PWR0606"
			(at 138.43 146.05 0)
			(effects
				(font
					(size 1.27 1.27)
				)
				(justify left bottom)
				(hide yes)
			)
		)
		(property "Value" "GND"
			(at 138.43 144.78 0)
			(effects
				(font
					(size 1.27 1.27)
				)
			)
		)
		(property "Footprint" ""
			(at 138.43 139.7 0)
			(effects
				(font
					(size 1.27 1.27)
				)
				(hide yes)
			)
		)
		(property "Datasheet" ""
			(at 138.43 139.7 0)
			(effects
				(font
					(size 1.27 1.27)
				)
				(hide yes)
			)
		)
		(property "Description" ""
			(at 138.43 139.7 0)
			(effects
				(font
					(size 1.27 1.27)
				)
				(hide yes)
			)
		)
		(property "Author" "Antmicro"
			(at 147.32 147.32 0)
			(effects
				(font
					(size 1.27 1.27)
					(thickness 0.15)
				)
				(justify left bottom)
				(hide yes)
			)
		)
		(property "License" "Apache-2.0"
			(at 147.32 149.86 0)
			(effects
				(font
					(size 1.27 1.27)
					(thickness 0.15)
				)
				(justify left bottom)
				(hide yes)
			)
		)
		(pin "1"
		)
		(instances
			(project "cm4-baseboard"
				(path ""
					(reference "#PWR0606")
					(unit 1)
				)
			)
		)
	)
	(symbol
		(lib_id "antmicroLEDIndicationDiscrete:LED_G_0603_KP-1608CGCK")
		(at 152.4 142.24 270)
		(mirror x)
		(unit 1)
		(exclude_from_sim no)
		(in_bom yes)
		(on_board yes)
		(dnp no)
		(property "Reference" "D601"
			(at 158.75 138.43 90)
			(effects
				(font
					(size 1.27 1.27)
					(thickness 0.15)
				)
			)
		)
		(property "Value" "LED_G_0603_KP-1608CGCK"
			(at 144.78 119.38 0)
			(effects
				(font
					(size 1.27 1.27)
					(thickness 0.15)
				)
				(justify left bottom)
				(hide yes)
			)
		)
		(property "Footprint" "antmicro-footprints:LED_0603_1608Metric_G"
			(at 142.24 119.38 0)
			(effects
				(font
					(size 1.27 1.27)
					(thickness 0.15)
				)
				(justify left bottom)
				(hide yes)
			)
		)
		(property "Datasheet" "http://www.kingbright.com/attachments/file/psearch//000/00/00/KP-1608CGCK(Ver.23B).pdf"
			(at 139.7 119.38 0)
			(effects
				(font
					(size 1.27 1.27)
					(thickness 0.15)
				)
				(justify left bottom)
				(hide yes)
			)
		)
		(property "Description" ""
			(at 152.4 142.24 0)
			(effects
				(font
					(size 1.27 1.27)
				)
				(hide yes)
			)
		)
		(property "MPN" "KP-1608CGCK"
			(at 137.16 119.38 0)
			(effects
				(font
					(size 1.27 1.27)
					(thickness 0.15)
				)
				(justify left bottom)
				(hide yes)
			)
		)
		(property "Manufacturer" "Kingbright"
			(at 134.62 119.38 0)
			(effects
				(font
					(size 1.27 1.27)
					(thickness 0.15)
				)
				(justify left bottom)
				(hide yes)
			)
		)
		(property "Color" "Green"
			(at 158.75 140.97 90)
			(effects
				(font
					(size 1.27 1.27)
				)
			)
		)
		(property "Author" "Antmicro"
			(at 132.08 119.38 0)
			(effects
				(font
					(size 1.27 1.27)
					(thickness 0.15)
				)
				(justify left bottom)
				(hide yes)
			)
		)
		(property "License" "Apache-2.0"
			(at 129.54 119.38 0)
			(effects
				(font
					(size 1.27 1.27)
					(thickness 0.15)
				)
				(justify left bottom)
				(hide yes)
			)
		)
		(pin "2"
		)
		(pin "1"
		)
		(instances
			(project "cm4-baseboard"
				(path ""
					(reference "D601")
					(unit 1)
				)
			)
		)
	)
	(symbol
		(lib_id "antmicroResistors0402:R_470R_0402")
		(at 152.4 180.34 90)
		(unit 1)
		(exclude_from_sim no)
		(in_bom yes)
		(on_board yes)
		(dnp no)
		(fields_autoplaced yes)
		(property "Reference" "R607"
			(at 154.94 176.5299 90)
			(effects
				(font
					(size 1.27 1.27)
				)
				(justify right)
			)
		)
		(property "Value" "R_470R_0402"
			(at 165.1 160.02 0)
			(effects
				(font
					(size 1.27 1.27)
					(thickness 0.15)
				)
				(justify left bottom)
				(hide yes)
			)
		)
		(property "Footprint" "antmicro-footprints:R_0402_1005Metric"
			(at 167.64 160.02 0)
			(effects
				(font
					(size 1.27 1.27)
					(thickness 0.15)
				)
				(justify left bottom)
				(hide yes)
			)
		)
		(property "Datasheet" "https://www.bourns.com/docs/product-datasheets/cr.pdf"
			(at 170.18 160.02 0)
			(effects
				(font
					(size 1.27 1.27)
					(thickness 0.15)
				)
				(justify left bottom)
				(hide yes)
			)
		)
		(property "Description" ""
			(at 152.4 180.34 0)
			(effects
				(font
					(size 1.27 1.27)
				)
				(hide yes)
			)
		)
		(property "Manufacturer" "Bourns"
			(at 175.26 160.02 0)
			(effects
				(font
					(size 1.27 1.27)
					(thickness 0.15)
				)
				(justify left bottom)
				(hide yes)
			)
		)
		(property "MPN" "CR0402-FX-4700GLF"
			(at 172.72 160.02 0)
			(effects
				(font
					(size 1.27 1.27)
					(thickness 0.15)
				)
				(justify left bottom)
				(hide yes)
			)
		)
		(property "Val" "470R"
			(at 154.94 179.0699 90)
			(effects
				(font
					(size 1.27 1.27)
					(thickness 0.15)
				)
				(justify right)
			)
		)
		(property "License" "Apache-2.0"
			(at 177.8 160.02 0)
			(effects
				(font
					(size 1.27 1.27)
					(thickness 0.15)
				)
				(justify left bottom)
				(hide yes)
			)
		)
		(property "Author" "Antmicro"
			(at 180.34 160.02 0)
			(effects
				(font
					(size 1.27 1.27)
					(thickness 0.15)
				)
				(justify left bottom)
				(hide yes)
			)
		)
		(property "Tolerance" "1%"
			(at 162.56 160.02 0)
			(effects
				(font
					(size 1.27 1.27)
				)
				(justify left bottom)
				(hide yes)
			)
		)
		(pin "1"
		)
		(pin "2"
		)
		(instances
			(project "cm4-baseboard"
				(path ""
					(reference "R607")
					(unit 1)
				)
			)
		)
	)
	(symbol
		(lib_id "antmicroLEDIndicationDiscrete:LED_G_0603_KP-1608CGCK")
		(at 152.4 186.69 270)
		(mirror x)
		(unit 1)
		(exclude_from_sim no)
		(in_bom yes)
		(on_board yes)
		(dnp no)
		(property "Reference" "D602"
			(at 158.75 182.88 90)
			(effects
				(font
					(size 1.27 1.27)
					(thickness 0.15)
				)
			)
		)
		(property "Value" "LED_G_0603_KP-1608CGCK"
			(at 144.78 163.83 0)
			(effects
				(font
					(size 1.27 1.27)
					(thickness 0.15)
				)
				(justify left bottom)
				(hide yes)
			)
		)
		(property "Footprint" "antmicro-footprints:LED_0603_1608Metric_G"
			(at 142.24 163.83 0)
			(effects
				(font
					(size 1.27 1.27)
					(thickness 0.15)
				)
				(justify left bottom)
				(hide yes)
			)
		)
		(property "Datasheet" "http://www.kingbright.com/attachments/file/psearch//000/00/00/KP-1608CGCK(Ver.23B).pdf"
			(at 139.7 163.83 0)
			(effects
				(font
					(size 1.27 1.27)
					(thickness 0.15)
				)
				(justify left bottom)
				(hide yes)
			)
		)
		(property "Description" ""
			(at 152.4 186.69 0)
			(effects
				(font
					(size 1.27 1.27)
				)
				(hide yes)
			)
		)
		(property "MPN" "KP-1608CGCK"
			(at 137.16 163.83 0)
			(effects
				(font
					(size 1.27 1.27)
					(thickness 0.15)
				)
				(justify left bottom)
				(hide yes)
			)
		)
		(property "Manufacturer" "Kingbright"
			(at 134.62 163.83 0)
			(effects
				(font
					(size 1.27 1.27)
					(thickness 0.15)
				)
				(justify left bottom)
				(hide yes)
			)
		)
		(property "Color" "Green"
			(at 158.75 185.42 90)
			(effects
				(font
					(size 1.27 1.27)
				)
			)
		)
		(property "Author" "Antmicro"
			(at 132.08 163.83 0)
			(effects
				(font
					(size 1.27 1.27)
					(thickness 0.15)
				)
				(justify left bottom)
				(hide yes)
			)
		)
		(property "License" "Apache-2.0"
			(at 129.54 163.83 0)
			(effects
				(font
					(size 1.27 1.27)
					(thickness 0.15)
				)
				(justify left bottom)
				(hide yes)
			)
		)
		(pin "2"
		)
		(pin "1"
		)
		(instances
			(project "cm4-baseboard"
				(path ""
					(reference "D602")
					(unit 1)
				)
			)
		)
	)
	(symbol
		(lib_id "antmicroResistors0402:R_10k_0402")
		(at 118.11 120.65 270)
		(unit 1)
		(exclude_from_sim no)
		(in_bom yes)
		(on_board yes)
		(dnp no)
		(property "Reference" "R602"
			(at 116.84 121.92 90)
			(effects
				(font
					(size 1.27 1.27)
				)
				(justify right)
			)
		)
		(property "Value" "R_10k_0402"
			(at 105.41 140.97 0)
			(effects
				(font
					(size 1.27 1.27)
					(thickness 0.15)
				)
				(justify left bottom)
				(hide yes)
			)
		)
		(property "Footprint" "antmicro-footprints:R_0402_1005Metric"
			(at 102.87 140.97 0)
			(effects
				(font
					(size 1.27 1.27)
					(thickness 0.15)
				)
				(justify left bottom)
				(hide yes)
			)
		)
		(property "Datasheet" "https://www.bourns.com/docs/product-datasheets/cr.pdf"
			(at 100.33 140.97 0)
			(effects
				(font
					(size 1.27 1.27)
					(thickness 0.15)
				)
				(justify left bottom)
				(hide yes)
			)
		)
		(property "Description" ""
			(at 118.11 120.65 0)
			(effects
				(font
					(size 1.27 1.27)
				)
				(hide yes)
			)
		)
		(property "Manufacturer" "Bourns"
			(at 95.25 140.97 0)
			(effects
				(font
					(size 1.27 1.27)
					(thickness 0.15)
				)
				(justify left bottom)
				(hide yes)
			)
		)
		(property "MPN" "CR0402-FX-1002GLF"
			(at 97.79 140.97 0)
			(effects
				(font
					(size 1.27 1.27)
					(thickness 0.15)
				)
				(justify left bottom)
				(hide yes)
			)
		)
		(property "Val" "10k"
			(at 116.84 124.46 90)
			(effects
				(font
					(size 1.27 1.27)
					(thickness 0.15)
				)
				(justify right)
			)
		)
		(property "License" "Apache-2.0"
			(at 92.71 140.97 0)
			(effects
				(font
					(size 1.27 1.27)
					(thickness 0.15)
				)
				(justify left bottom)
				(hide yes)
			)
		)
		(property "Author" "Antmicro"
			(at 90.17 140.97 0)
			(effects
				(font
					(size 1.27 1.27)
					(thickness 0.15)
				)
				(justify left bottom)
				(hide yes)
			)
		)
		(property "Tolerance" "1%"
			(at 107.95 140.97 0)
			(effects
				(font
					(size 1.27 1.27)
				)
				(justify left bottom)
				(hide yes)
			)
		)
		(pin "1"
		)
		(pin "2"
		)
		(instances
			(project "cm4-baseboard"
				(path ""
					(reference "R602")
					(unit 1)
				)
			)
		)
	)
	(symbol
		(lib_id "antmicroPMICPowerDistributionSwitchesLoadDrivers:AP22615A_TSOT26")
		(at 121.92 173.99 0)
		(unit 1)
		(exclude_from_sim no)
		(in_bom yes)
		(on_board yes)
		(dnp no)
		(property "Reference" "U602"
			(at 129.54 167.64 0)
			(effects
				(font
					(size 1.27 1.27)
				)
			)
		)
		(property "Value" "AP22615A_TSOT26"
			(at 129.54 170.18 0)
			(effects
				(font
					(size 1.27 1.27)
					(thickness 0.15)
				)
				(hide yes)
			)
		)
		(property "Footprint" "antmicro-footprints:TSOT23-6"
			(at 152.4 181.61 0)
			(effects
				(font
					(size 1.27 1.27)
					(thickness 0.15)
				)
				(justify left bottom)
				(hide yes)
			)
		)
		(property "Datasheet" "https://www.mouser.com/datasheet/2/115/DIOD_S_A0008958405_1-2543193.pdf"
			(at 152.4 184.15 0)
			(effects
				(font
					(size 1.27 1.27)
					(thickness 0.15)
				)
				(justify left bottom)
				(hide yes)
			)
		)
		(property "Description" ""
			(at 121.92 173.99 0)
			(effects
				(font
					(size 1.27 1.27)
				)
				(hide yes)
			)
		)
		(property "MPN" "AP22615AWU-7"
			(at 129.54 170.18 0)
			(effects
				(font
					(size 1.27 1.27)
					(thickness 0.15)
				)
			)
		)
		(property "Manufacturer" "Diodes Incorporated"
			(at 152.4 189.23 0)
			(effects
				(font
					(size 1.27 1.27)
					(thickness 0.15)
				)
				(justify left bottom)
				(hide yes)
			)
		)
		(property "Author" "Antmicro"
			(at 152.4 191.77 0)
			(effects
				(font
					(size 1.27 1.27)
					(thickness 0.15)
				)
				(justify left bottom)
				(hide yes)
			)
		)
		(property "License" "Apache-2.0"
			(at 152.4 194.31 0)
			(effects
				(font
					(size 1.27 1.27)
					(thickness 0.15)
				)
				(justify left bottom)
				(hide yes)
			)
		)
		(pin "1"
		)
		(pin "2"
		)
		(pin "3"
		)
		(pin "4"
		)
		(pin "5"
		)
		(pin "6"
		)
		(instances
			(project "cm4-baseboard"
				(path ""
					(reference "U602")
					(unit 1)
				)
			)
		)
	)
	(symbol
		(lib_id "antmicroTestPoints:TP_0.75mm_SMD")
		(at 116.84 132.08 0)
		(mirror y)
		(unit 1)
		(exclude_from_sim no)
		(in_bom no)
		(on_board yes)
		(dnp no)
		(fields_autoplaced yes)
		(property "Reference" "TP601"
			(at 111.76 132.0799 0)
			(effects
				(font
					(size 1.27 1.27)
				)
				(justify left)
			)
		)
		(property "Value" "TP_0.75mm_SMD"
			(at 101.6 139.7 0)
			(effects
				(font
					(size 1.27 1.27)
					(thickness 0.15)
				)
				(justify left bottom)
				(hide yes)
			)
		)
		(property "Footprint" "antmicro-footprints:TP_SMD_0.75mm"
			(at 101.6 142.24 0)
			(effects
				(font
					(size 1.27 1.27)
					(thickness 0.15)
				)
				(justify left bottom)
				(hide yes)
			)
		)
		(property "Datasheet" ""
			(at 101.6 144.78 0)
			(effects
				(font
					(size 1.27 1.27)
					(thickness 0.15)
				)
				(justify left bottom)
				(hide yes)
			)
		)
		(property "Description" ""
			(at 116.84 132.08 0)
			(effects
				(font
					(size 1.27 1.27)
				)
				(hide yes)
			)
		)
		(property "MPN" ""
			(at 116.84 132.08 0)
			(effects
				(font
					(size 1.27 1.27)
				)
				(hide yes)
			)
		)
		(property "Manufacturer" ""
			(at 116.84 132.08 0)
			(effects
				(font
					(size 1.27 1.27)
				)
				(hide yes)
			)
		)
		(property "Author" "Antmicro"
			(at 101.6 147.32 0)
			(effects
				(font
					(size 1.27 1.27)
					(thickness 0.15)
				)
				(justify left bottom)
				(hide yes)
			)
		)
		(property "License" "Apache-2.0"
			(at 101.6 149.86 0)
			(effects
				(font
					(size 1.27 1.27)
					(thickness 0.15)
				)
				(justify left bottom)
				(hide yes)
			)
		)
		(pin "1"
		)
		(instances
			(project "cm4-baseboard"
				(path ""
					(reference "TP601")
					(unit 1)
				)
			)
		)
	)
	(symbol
		(lib_id "antmicropower:GND")
		(at 93.98 144.78 0)
		(unit 1)
		(exclude_from_sim no)
		(in_bom yes)
		(on_board yes)
		(dnp no)
		(fields_autoplaced yes)
		(property "Reference" "#PWR0601"
			(at 93.98 151.13 0)
			(effects
				(font
					(size 1.27 1.27)
				)
				(justify left bottom)
				(hide yes)
			)
		)
		(property "Value" "GND"
			(at 93.98 149.86 0)
			(effects
				(font
					(size 1.27 1.27)
				)
			)
		)
		(property "Footprint" ""
			(at 93.98 144.78 0)
			(effects
				(font
					(size 1.27 1.27)
				)
				(hide yes)
			)
		)
		(property "Datasheet" ""
			(at 93.98 144.78 0)
			(effects
				(font
					(size 1.27 1.27)
				)
				(hide yes)
			)
		)
		(property "Description" ""
			(at 93.98 144.78 0)
			(effects
				(font
					(size 1.27 1.27)
				)
				(hide yes)
			)
		)
		(property "Author" "Antmicro"
			(at 102.87 152.4 0)
			(effects
				(font
					(size 1.27 1.27)
					(thickness 0.15)
				)
				(justify left bottom)
				(hide yes)
			)
		)
		(property "License" "Apache-2.0"
			(at 102.87 154.94 0)
			(effects
				(font
					(size 1.27 1.27)
					(thickness 0.15)
				)
				(justify left bottom)
				(hide yes)
			)
		)
		(pin "1"
		)
		(instances
			(project "cm4-baseboard"
				(path ""
					(reference "#PWR0601")
					(unit 1)
				)
			)
		)
	)
	(symbol
		(lib_id "antmicropower:GND")
		(at 138.43 184.15 0)
		(unit 1)
		(exclude_from_sim no)
		(in_bom yes)
		(on_board yes)
		(dnp no)
		(fields_autoplaced yes)
		(property "Reference" "#PWR0607"
			(at 138.43 190.5 0)
			(effects
				(font
					(size 1.27 1.27)
				)
				(justify left bottom)
				(hide yes)
			)
		)
		(property "Value" "GND"
			(at 138.43 189.23 0)
			(effects
				(font
					(size 1.27 1.27)
				)
			)
		)
		(property "Footprint" ""
			(at 138.43 184.15 0)
			(effects
				(font
					(size 1.27 1.27)
				)
				(hide yes)
			)
		)
		(property "Datasheet" ""
			(at 138.43 184.15 0)
			(effects
				(font
					(size 1.27 1.27)
				)
				(hide yes)
			)
		)
		(property "Description" ""
			(at 138.43 184.15 0)
			(effects
				(font
					(size 1.27 1.27)
				)
				(hide yes)
			)
		)
		(property "Author" "Antmicro"
			(at 147.32 191.77 0)
			(effects
				(font
					(size 1.27 1.27)
					(thickness 0.15)
				)
				(justify left bottom)
				(hide yes)
			)
		)
		(property "License" "Apache-2.0"
			(at 147.32 194.31 0)
			(effects
				(font
					(size 1.27 1.27)
					(thickness 0.15)
				)
				(justify left bottom)
				(hide yes)
			)
		)
		(pin "1"
		)
		(instances
			(project "cm4-baseboard"
				(path ""
					(reference "#PWR0607")
					(unit 1)
				)
			)
		)
	)
	(symbol
		(lib_id "antmicropower:GND")
		(at 299.72 193.04 0)
		(unit 1)
		(exclude_from_sim no)
		(in_bom yes)
		(on_board yes)
		(dnp no)
		(property "Reference" "#PWR0612"
			(at 299.72 199.39 0)
			(effects
				(font
					(size 1.27 1.27)
				)
				(justify left bottom)
				(hide yes)
			)
		)
		(property "Value" "GND"
			(at 299.72 196.85 0)
			(effects
				(font
					(size 1.27 1.27)
				)
			)
		)
		(property "Footprint" ""
			(at 299.72 193.04 0)
			(effects
				(font
					(size 1.27 1.27)
				)
				(hide yes)
			)
		)
		(property "Datasheet" ""
			(at 299.72 193.04 0)
			(effects
				(font
					(size 1.27 1.27)
				)
				(hide yes)
			)
		)
		(property "Description" ""
			(at 299.72 193.04 0)
			(effects
				(font
					(size 1.27 1.27)
				)
				(hide yes)
			)
		)
		(property "Author" "Antmicro"
			(at 308.61 200.66 0)
			(effects
				(font
					(size 1.27 1.27)
					(thickness 0.15)
				)
				(justify left bottom)
				(hide yes)
			)
		)
		(property "License" "Apache-2.0"
			(at 308.61 203.2 0)
			(effects
				(font
					(size 1.27 1.27)
					(thickness 0.15)
				)
				(justify left bottom)
				(hide yes)
			)
		)
		(pin "1"
		)
		(instances
			(project "cm4-baseboard"
				(path ""
					(reference "#PWR0612")
					(unit 1)
				)
			)
		)
	)
	(symbol
		(lib_id "antmicroTestPoints:TP_0.75mm_SMD")
		(at 152.4 128.27 90)
		(unit 1)
		(exclude_from_sim no)
		(in_bom no)
		(on_board yes)
		(dnp no)
		(fields_autoplaced yes)
		(property "Reference" "TP603"
			(at 154.305 125.0949 90)
			(effects
				(font
					(size 1.27 1.27)
				)
				(justify right)
			)
		)
		(property "Value" "TP_0.75mm_SMD"
			(at 154.94 128.27 0)
			(effects
				(font
					(size 1.27 1.27)
					(thickness 0.15)
				)
				(justify left bottom)
				(hide yes)
			)
		)
		(property "Footprint" "antmicro-footprints:TP_SMD_0.75mm"
			(at 147.32 123.19 0)
			(effects
				(font
					(size 1.27 1.27)
					(thickness 0.15)
				)
				(justify left bottom)
				(hide yes)
			)
		)
		(property "Datasheet" ""
			(at 144.78 123.19 0)
			(effects
				(font
					(size 1.27 1.27)
					(thickness 0.15)
				)
				(justify left bottom)
				(hide yes)
			)
		)
		(property "Description" ""
			(at 152.4 128.27 0)
			(effects
				(font
					(size 1.27 1.27)
				)
				(hide yes)
			)
		)
		(property "MPN" ""
			(at 152.4 128.27 0)
			(effects
				(font
					(size 1.27 1.27)
					(thickness 0.15)
				)
				(justify left bottom)
				(hide yes)
			)
		)
		(property "Manufacturer" ""
			(at 152.4 128.27 0)
			(effects
				(font
					(size 1.27 1.27)
					(thickness 0.15)
				)
				(justify left bottom)
				(hide yes)
			)
		)
		(property "Author" "Antmicro"
			(at 167.64 113.03 0)
			(effects
				(font
					(size 1.27 1.27)
					(thickness 0.15)
				)
				(justify left bottom)
				(hide yes)
			)
		)
		(property "License" "Apache-2.0"
			(at 170.18 113.03 0)
			(effects
				(font
					(size 1.27 1.27)
					(thickness 0.15)
				)
				(justify left bottom)
				(hide yes)
			)
		)
		(pin "1"
		)
		(instances
			(project "cm4-baseboard"
				(path ""
					(reference "TP603")
					(unit 1)
				)
			)
		)
	)
	(symbol
		(lib_id "antmicroResistors0402:R_100k_0402")
		(at 93.98 142.24 90)
		(unit 1)
		(exclude_from_sim no)
		(in_bom yes)
		(on_board yes)
		(dnp no)
		(property "Reference" "R601"
			(at 95.25 138.4301 90)
			(effects
				(font
					(size 1.27 1.27)
				)
				(justify right)
			)
		)
		(property "Value" "R_100k_0402"
			(at 106.68 121.92 0)
			(effects
				(font
					(size 1.27 1.27)
					(thickness 0.15)
				)
				(justify left bottom)
				(hide yes)
			)
		)
		(property "Footprint" "antmicro-footprints:R_0402_1005Metric"
			(at 109.22 121.92 0)
			(effects
				(font
					(size 1.27 1.27)
					(thickness 0.15)
				)
				(justify left bottom)
				(hide yes)
			)
		)
		(property "Datasheet" "https://www.bourns.com/docs/product-datasheets/cr.pdf"
			(at 111.76 121.92 0)
			(effects
				(font
					(size 1.27 1.27)
					(thickness 0.15)
				)
				(justify left bottom)
				(hide yes)
			)
		)
		(property "Description" ""
			(at 93.98 142.24 0)
			(effects
				(font
					(size 1.27 1.27)
				)
				(hide yes)
			)
		)
		(property "Manufacturer" "Bourns"
			(at 116.84 121.92 0)
			(effects
				(font
					(size 1.27 1.27)
					(thickness 0.15)
				)
				(justify left bottom)
				(hide yes)
			)
		)
		(property "MPN" "CR0402-FX-1003GLF"
			(at 114.3 121.92 0)
			(effects
				(font
					(size 1.27 1.27)
					(thickness 0.15)
				)
				(justify left bottom)
				(hide yes)
			)
		)
		(property "Val" "100k"
			(at 95.25 140.97 90)
			(effects
				(font
					(size 1.27 1.27)
					(thickness 0.15)
				)
				(justify right)
			)
		)
		(property "License" "Apache-2.0"
			(at 119.38 121.92 0)
			(effects
				(font
					(size 1.27 1.27)
					(thickness 0.15)
				)
				(justify left bottom)
				(hide yes)
			)
		)
		(property "Author" "Antmicro"
			(at 121.92 121.92 0)
			(effects
				(font
					(size 1.27 1.27)
					(thickness 0.15)
				)
				(justify left bottom)
				(hide yes)
			)
		)
		(property "Tolerance" "1%"
			(at 104.14 121.92 0)
			(effects
				(font
					(size 1.27 1.27)
				)
				(justify left bottom)
				(hide yes)
			)
		)
		(pin "1"
		)
		(pin "2"
		)
		(instances
			(project "cm4-baseboard"
				(path ""
					(reference "R601")
					(unit 1)
				)
			)
		)
	)
	(symbol
		(lib_id "antmicropower:GND")
		(at 316.23 193.04 0)
		(unit 1)
		(exclude_from_sim no)
		(in_bom yes)
		(on_board yes)
		(dnp no)
		(property "Reference" "#PWR0614"
			(at 316.23 199.39 0)
			(effects
				(font
					(size 1.27 1.27)
				)
				(justify left bottom)
				(hide yes)
			)
		)
		(property "Value" "GND"
			(at 316.23 196.85 0)
			(effects
				(font
					(size 1.27 1.27)
				)
			)
		)
		(property "Footprint" ""
			(at 316.23 193.04 0)
			(effects
				(font
					(size 1.27 1.27)
				)
				(hide yes)
			)
		)
		(property "Datasheet" ""
			(at 316.23 193.04 0)
			(effects
				(font
					(size 1.27 1.27)
				)
				(hide yes)
			)
		)
		(property "Description" ""
			(at 316.23 193.04 0)
			(effects
				(font
					(size 1.27 1.27)
				)
				(hide yes)
			)
		)
		(property "Author" "Antmicro"
			(at 325.12 200.66 0)
			(effects
				(font
					(size 1.27 1.27)
					(thickness 0.15)
				)
				(justify left bottom)
				(hide yes)
			)
		)
		(property "License" "Apache-2.0"
			(at 325.12 203.2 0)
			(effects
				(font
					(size 1.27 1.27)
					(thickness 0.15)
				)
				(justify left bottom)
				(hide yes)
			)
		)
		(pin "1"
		)
		(instances
			(project "cm4-baseboard"
				(path ""
					(reference "#PWR0614")
					(unit 1)
				)
			)
		)
	)
	(symbol
		(lib_id "antmicropower:GND")
		(at 278.13 193.04 0)
		(unit 1)
		(exclude_from_sim no)
		(in_bom yes)
		(on_board yes)
		(dnp no)
		(fields_autoplaced yes)
		(property "Reference" "#PWR02"
			(at 287.02 195.58 0)
			(effects
				(font
					(size 1.27 1.27)
					(thickness 0.15)
				)
				(justify left bottom)
				(hide yes)
			)
		)
		(property "Value" "GND"
			(at 276.1198 198.12 0)
			(effects
				(font
					(size 1.27 1.27)
					(thickness 0.15)
				)
				(justify left bottom)
			)
		)
		(property "Footprint" ""
			(at 287.02 200.66 0)
			(effects
				(font
					(size 1.27 1.27)
					(thickness 0.15)
				)
				(justify left bottom)
				(hide yes)
			)
		)
		(property "Datasheet" ""
			(at 287.02 205.74 0)
			(effects
				(font
					(size 1.27 1.27)
					(thickness 0.15)
				)
				(justify left bottom)
				(hide yes)
			)
		)
		(property "Description" ""
			(at 278.13 193.04 0)
			(effects
				(font
					(size 1.27 1.27)
				)
				(hide yes)
			)
		)
		(property "Author" "Antmicro"
			(at 287.02 200.66 0)
			(effects
				(font
					(size 1.27 1.27)
					(thickness 0.15)
				)
				(justify left bottom)
				(hide yes)
			)
		)
		(property "License" "Apache-2.0"
			(at 287.02 203.2 0)
			(effects
				(font
					(size 1.27 1.27)
					(thickness 0.15)
				)
				(justify left bottom)
				(hide yes)
			)
		)
		(pin "1"
		)
		(instances
			(project "cm4-baseboard"
				(path ""
					(reference "#PWR02")
					(unit 1)
				)
			)
		)
	)
	(symbol
		(lib_id "antmicropower:GND")
		(at 143.51 139.7 0)
		(unit 1)
		(exclude_from_sim no)
		(in_bom yes)
		(on_board yes)
		(dnp no)
		(fields_autoplaced yes)
		(property "Reference" "#PWR0608"
			(at 143.51 146.05 0)
			(effects
				(font
					(size 1.27 1.27)
				)
				(justify left bottom)
				(hide yes)
			)
		)
		(property "Value" "GND"
			(at 143.51 144.78 0)
			(effects
				(font
					(size 1.27 1.27)
				)
			)
		)
		(property "Footprint" ""
			(at 143.51 139.7 0)
			(effects
				(font
					(size 1.27 1.27)
				)
				(hide yes)
			)
		)
		(property "Datasheet" ""
			(at 143.51 139.7 0)
			(effects
				(font
					(size 1.27 1.27)
				)
				(hide yes)
			)
		)
		(property "Description" ""
			(at 143.51 139.7 0)
			(effects
				(font
					(size 1.27 1.27)
				)
				(hide yes)
			)
		)
		(property "Author" "Antmicro"
			(at 152.4 147.32 0)
			(effects
				(font
					(size 1.27 1.27)
					(thickness 0.15)
				)
				(justify left bottom)
				(hide yes)
			)
		)
		(property "License" "Apache-2.0"
			(at 152.4 149.86 0)
			(effects
				(font
					(size 1.27 1.27)
					(thickness 0.15)
				)
				(justify left bottom)
				(hide yes)
			)
		)
		(pin "1"
		)
		(instances
			(project "cm4-baseboard"
				(path ""
					(reference "#PWR0608")
					(unit 1)
				)
			)
		)
	)
	(symbol
		(lib_id "antmicropower:+5V")
		(at 109.22 118.11 0)
		(unit 1)
		(exclude_from_sim no)
		(in_bom yes)
		(on_board yes)
		(dnp no)
		(fields_autoplaced yes)
		(property "Reference" "#PWR0602"
			(at 109.22 121.92 0)
			(effects
				(font
					(size 1.27 1.27)
				)
				(justify left bottom)
				(hide yes)
			)
		)
		(property "Value" "+5V"
			(at 109.22 113.03 0)
			(effects
				(font
					(size 1.27 1.27)
				)
			)
		)
		(property "Footprint" ""
			(at 109.22 118.11 0)
			(effects
				(font
					(size 1.27 1.27)
				)
				(hide yes)
			)
		)
		(property "Datasheet" ""
			(at 109.22 118.11 0)
			(effects
				(font
					(size 1.27 1.27)
				)
				(hide yes)
			)
		)
		(property "Description" ""
			(at 109.22 118.11 0)
			(effects
				(font
					(size 1.27 1.27)
				)
				(hide yes)
			)
		)
		(property "Author" "Antmicro"
			(at 124.46 125.73 0)
			(effects
				(font
					(size 1.27 1.27)
					(thickness 0.15)
				)
				(justify left bottom)
				(hide yes)
			)
		)
		(property "License" "Apache-2.0"
			(at 124.46 128.27 0)
			(effects
				(font
					(size 1.27 1.27)
					(thickness 0.15)
				)
				(justify left bottom)
				(hide yes)
			)
		)
		(pin "1"
		)
		(instances
			(project "cm4-baseboard"
				(path ""
					(reference "#PWR0602")
					(unit 1)
				)
			)
		)
	)
)
